FILE_TYPE = MACRO_DRAWING;
SET COLOR_WIRE YELLOW;
SET COLOR_PROP ORANGE;
SET COLOR_DOT WHITE;
SET COLOR_ARC YELLOW;
SET COLOR_BODY GREEN;
SET COLOR_NOTE PURPLE;
SET PROP_DISPLAY VALUE;
SET PAGE_NUMBER P57;
FORCEADD VCC_CORE..1
(-7425 6600);
FORCEPROP 3 LASTPIN (-7425 6550) SIG_NAME PVDDCR_CPU0_P1\g
J 0
(-7415 6560);
DISPLAY 0.659574 (-7415 6560);
PAINT MONO (-7415 6560);
DISPLAY INVISIBLE (-7415 6560);
FORCEPROP 1 LAST HDL_POWER PVDDCR_CPU0_P1
J 1
(-7425 6650);
DISPLAY 0.489362 (-7425 6650);
PAINT GREEN (-7425 6650);
FORCEPROP 2 LAST CDS_LIB pure_quanta_power
J 0
(-7425 6600);
DISPLAY INVISIBLE (-7425 6600);
FORCEPROP 1 LAST PATH I27
J 0
(-7375 6625);
DISPLAY 0.872340 (-7375 6625);
PAINT AQUA (-7375 6625);
DISPLAY INVISIBLE (-7375 6625);
FORCEADD VCC_CORE..1
(-8875 6600);
FORCEPROP 3 LASTPIN (-8875 6550) SIG_NAME PVDDCR_CPU0_P1\g
J 0
(-8865 6560);
DISPLAY 0.659574 (-8865 6560);
PAINT MONO (-8865 6560);
DISPLAY INVISIBLE (-8865 6560);
FORCEPROP 1 LAST HDL_POWER PVDDCR_CPU0_P1
J 1
(-8875 6650);
DISPLAY 0.489362 (-8875 6650);
PAINT GREEN (-8875 6650);
FORCEPROP 2 LAST CDS_LIB pure_quanta_power
J 0
(-8875 6600);
DISPLAY INVISIBLE (-8875 6600);
FORCEPROP 1 LAST PATH I28
J 0
(-8825 6625);
DISPLAY 0.872340 (-8825 6625);
PAINT AQUA (-8825 6625);
DISPLAY INVISIBLE (-8825 6625);
FORCEADD GENOA_SP5..24
(-8150 3350);
FORCEPROP 1 LAST LOCATION U26
J 0
(-8650 6600);
DISPLAY 0.489362 (-8650 6600);
PAINT SKYBLUE (-8650 6600);
FORCEPROP 0 LAST $SEC 24
J 0
(-8625 6850);
DISPLAY 0.680851 (-8625 6850);
PAINT MONO (-8625 6850);
DISPLAY INVISIBLE (-8625 6850);
FORCEPROP 0 LAST CDS_SEC 24
J 0
(-8625 6850);
DISPLAY 1.021277 (-8625 6850);
DISPLAY INVISIBLE (-8625 6850);
FORCEPROP 0 LASTPIN (-7500 5950) $PN AB23
J 0
(-7490 5960);
DISPLAY 0.489362 (-7490 5960);
PAINT MONO (-7490 5960);
FORCEPROP 0 LASTPIN (-7500 5900) $PN AB24
J 0
(-7490 5910);
DISPLAY 0.489362 (-7490 5910);
PAINT MONO (-7490 5910);
FORCEPROP 0 LASTPIN (-7500 5850) $PN AB26
J 0
(-7490 5860);
DISPLAY 0.489362 (-7490 5860);
PAINT MONO (-7490 5860);
FORCEPROP 0 LASTPIN (-7500 5800) $PN AB27
J 0
(-7490 5810);
DISPLAY 0.489362 (-7490 5810);
PAINT MONO (-7490 5810);
FORCEPROP 0 LASTPIN (-7500 5750) $PN AB29
J 0
(-7490 5760);
DISPLAY 0.489362 (-7490 5760);
PAINT MONO (-7490 5760);
FORCEPROP 0 LASTPIN (-7500 5700) $PN AB30
J 0
(-7490 5710);
DISPLAY 0.489362 (-7490 5710);
PAINT MONO (-7490 5710);
FORCEPROP 0 LASTPIN (-7500 5650) $PN AB32
J 0
(-7490 5660);
DISPLAY 0.489362 (-7490 5660);
PAINT MONO (-7490 5660);
FORCEPROP 0 LASTPIN (-7500 5600) $PN AB33
J 0
(-7490 5610);
DISPLAY 0.489362 (-7490 5610);
PAINT MONO (-7490 5610);
FORCEPROP 0 LASTPIN (-7500 5550) $PN AB43
J 0
(-7490 5560);
DISPLAY 0.489362 (-7490 5560);
PAINT MONO (-7490 5560);
FORCEPROP 0 LASTPIN (-7500 5500) $PN AB44
J 0
(-7490 5510);
DISPLAY 0.489362 (-7490 5510);
PAINT MONO (-7490 5510);
FORCEPROP 0 LASTPIN (-7500 5450) $PN AB46
J 0
(-7490 5460);
DISPLAY 0.489362 (-7490 5460);
PAINT MONO (-7490 5460);
FORCEPROP 0 LASTPIN (-7500 5400) $PN AB47
J 0
(-7490 5410);
DISPLAY 0.489362 (-7490 5410);
PAINT MONO (-7490 5410);
FORCEPROP 0 LASTPIN (-7500 5350) $PN AB49
J 0
(-7490 5360);
DISPLAY 0.489362 (-7490 5360);
PAINT MONO (-7490 5360);
FORCEPROP 0 LASTPIN (-7500 5300) $PN AB50
J 0
(-7490 5310);
DISPLAY 0.489362 (-7490 5310);
PAINT MONO (-7490 5310);
FORCEPROP 0 LASTPIN (-7500 5250) $PN AB52
J 0
(-7490 5260);
DISPLAY 0.489362 (-7490 5260);
PAINT MONO (-7490 5260);
FORCEPROP 0 LASTPIN (-7500 5200) $PN AB53
J 0
(-7490 5210);
DISPLAY 0.489362 (-7490 5210);
PAINT MONO (-7490 5210);
FORCEPROP 0 LASTPIN (-7500 5150) $PN AC35
J 0
(-7490 5160);
DISPLAY 0.489362 (-7490 5160);
PAINT MONO (-7490 5160);
FORCEPROP 0 LASTPIN (-7500 5100) $PN AC36
J 0
(-7490 5110);
DISPLAY 0.489362 (-7490 5110);
PAINT MONO (-7490 5110);
FORCEPROP 0 LASTPIN (-7500 5050) $PN AC40
J 0
(-7490 5060);
DISPLAY 0.489362 (-7490 5060);
PAINT MONO (-7490 5060);
FORCEPROP 0 LASTPIN (-7500 5000) $PN AC41
J 0
(-7490 5010);
DISPLAY 0.489362 (-7490 5010);
PAINT MONO (-7490 5010);
FORCEPROP 0 LASTPIN (-7500 4950) $PN AF23
J 0
(-7490 4960);
DISPLAY 0.489362 (-7490 4960);
PAINT MONO (-7490 4960);
FORCEPROP 0 LASTPIN (-7500 4900) $PN AF24
J 0
(-7490 4910);
DISPLAY 0.489362 (-7490 4910);
PAINT MONO (-7490 4910);
FORCEPROP 0 LASTPIN (-7500 4850) $PN AF26
J 0
(-7490 4860);
DISPLAY 0.489362 (-7490 4860);
PAINT MONO (-7490 4860);
FORCEPROP 0 LASTPIN (-7500 4800) $PN AF27
J 0
(-7490 4810);
DISPLAY 0.489362 (-7490 4810);
PAINT MONO (-7490 4810);
FORCEPROP 0 LASTPIN (-7500 4750) $PN AF29
J 0
(-7490 4760);
DISPLAY 0.489362 (-7490 4760);
PAINT MONO (-7490 4760);
FORCEPROP 0 LASTPIN (-7500 4700) $PN AF30
J 0
(-7490 4710);
DISPLAY 0.489362 (-7490 4710);
PAINT MONO (-7490 4710);
FORCEPROP 0 LASTPIN (-7500 4650) $PN AF32
J 0
(-7490 4660);
DISPLAY 0.489362 (-7490 4660);
PAINT MONO (-7490 4660);
FORCEPROP 0 LASTPIN (-7500 4600) $PN AF33
J 0
(-7490 4610);
DISPLAY 0.489362 (-7490 4610);
PAINT MONO (-7490 4610);
FORCEPROP 0 LASTPIN (-7500 4550) $PN AF43
J 0
(-7490 4560);
DISPLAY 0.489362 (-7490 4560);
PAINT MONO (-7490 4560);
FORCEPROP 0 LASTPIN (-7500 4500) $PN AF44
J 0
(-7490 4510);
DISPLAY 0.489362 (-7490 4510);
PAINT MONO (-7490 4510);
FORCEPROP 0 LASTPIN (-7500 4450) $PN AF46
J 0
(-7490 4460);
DISPLAY 0.489362 (-7490 4460);
PAINT MONO (-7490 4460);
FORCEPROP 0 LASTPIN (-7500 4400) $PN AF47
J 0
(-7490 4410);
DISPLAY 0.489362 (-7490 4410);
PAINT MONO (-7490 4410);
FORCEPROP 0 LASTPIN (-7500 4350) $PN AF49
J 0
(-7490 4360);
DISPLAY 0.489362 (-7490 4360);
PAINT MONO (-7490 4360);
FORCEPROP 0 LASTPIN (-7500 4300) $PN AF50
J 0
(-7490 4310);
DISPLAY 0.489362 (-7490 4310);
PAINT MONO (-7490 4310);
FORCEPROP 0 LASTPIN (-7500 4250) $PN AF52
J 0
(-7490 4260);
DISPLAY 0.489362 (-7490 4260);
PAINT MONO (-7490 4260);
FORCEPROP 0 LASTPIN (-7500 4200) $PN AF53
J 0
(-7490 4210);
DISPLAY 0.489362 (-7490 4210);
PAINT MONO (-7490 4210);
FORCEPROP 0 LASTPIN (-7500 4150) $PN AG35
J 0
(-7490 4160);
DISPLAY 0.489362 (-7490 4160);
PAINT MONO (-7490 4160);
FORCEPROP 0 LASTPIN (-7500 4100) $PN AG36
J 0
(-7490 4110);
DISPLAY 0.489362 (-7490 4110);
PAINT MONO (-7490 4110);
FORCEPROP 0 LASTPIN (-7500 4050) $PN AG40
J 0
(-7490 4060);
DISPLAY 0.489362 (-7490 4060);
PAINT MONO (-7490 4060);
FORCEPROP 0 LASTPIN (-7500 4000) $PN AG41
J 0
(-7490 4010);
DISPLAY 0.489362 (-7490 4010);
PAINT MONO (-7490 4010);
FORCEPROP 0 LASTPIN (-7500 3950) $PN AK23
J 0
(-7490 3960);
DISPLAY 0.489362 (-7490 3960);
PAINT MONO (-7490 3960);
FORCEPROP 0 LASTPIN (-7500 3900) $PN AK24
J 0
(-7490 3910);
DISPLAY 0.489362 (-7490 3910);
PAINT MONO (-7490 3910);
FORCEPROP 0 LASTPIN (-7500 3850) $PN AK26
J 0
(-7490 3860);
DISPLAY 0.489362 (-7490 3860);
PAINT MONO (-7490 3860);
FORCEPROP 0 LASTPIN (-7500 3800) $PN AK27
J 0
(-7490 3810);
DISPLAY 0.489362 (-7490 3810);
PAINT MONO (-7490 3810);
FORCEPROP 0 LASTPIN (-7500 3750) $PN AK29
J 0
(-7490 3760);
DISPLAY 0.489362 (-7490 3760);
PAINT MONO (-7490 3760);
FORCEPROP 0 LASTPIN (-7500 3700) $PN AK30
J 0
(-7490 3710);
DISPLAY 0.489362 (-7490 3710);
PAINT MONO (-7490 3710);
FORCEPROP 0 LASTPIN (-7500 3650) $PN AK32
J 0
(-7490 3660);
DISPLAY 0.489362 (-7490 3660);
PAINT MONO (-7490 3660);
FORCEPROP 0 LASTPIN (-7500 3600) $PN AK33
J 0
(-7490 3610);
DISPLAY 0.489362 (-7490 3610);
PAINT MONO (-7490 3610);
FORCEPROP 0 LASTPIN (-7500 3550) $PN AK43
J 0
(-7490 3560);
DISPLAY 0.489362 (-7490 3560);
PAINT MONO (-7490 3560);
FORCEPROP 0 LASTPIN (-7500 3500) $PN AK44
J 0
(-7490 3510);
DISPLAY 0.489362 (-7490 3510);
PAINT MONO (-7490 3510);
FORCEPROP 0 LASTPIN (-7500 3450) $PN AK46
J 0
(-7490 3460);
DISPLAY 0.489362 (-7490 3460);
PAINT MONO (-7490 3460);
FORCEPROP 0 LASTPIN (-7500 3400) $PN AK47
J 0
(-7490 3410);
DISPLAY 0.489362 (-7490 3410);
PAINT MONO (-7490 3410);
FORCEPROP 0 LASTPIN (-7500 3350) $PN AK49
J 0
(-7490 3360);
DISPLAY 0.489362 (-7490 3360);
PAINT MONO (-7490 3360);
FORCEPROP 0 LASTPIN (-7500 3300) $PN AK50
J 0
(-7490 3310);
DISPLAY 0.489362 (-7490 3310);
PAINT MONO (-7490 3310);
FORCEPROP 0 LASTPIN (-7500 3250) $PN AK52
J 0
(-7490 3260);
DISPLAY 0.489362 (-7490 3260);
PAINT MONO (-7490 3260);
FORCEPROP 0 LASTPIN (-7500 3200) $PN AK53
J 0
(-7490 3210);
DISPLAY 0.489362 (-7490 3210);
PAINT MONO (-7490 3210);
FORCEPROP 0 LASTPIN (-7500 3150) $PN AL35
J 0
(-7490 3160);
DISPLAY 0.489362 (-7490 3160);
PAINT MONO (-7490 3160);
FORCEPROP 0 LASTPIN (-7500 3100) $PN AL36
J 0
(-7490 3110);
DISPLAY 0.489362 (-7490 3110);
PAINT MONO (-7490 3110);
FORCEPROP 0 LASTPIN (-7500 3050) $PN AL40
J 0
(-7490 3060);
DISPLAY 0.489362 (-7490 3060);
PAINT MONO (-7490 3060);
FORCEPROP 0 LASTPIN (-7500 3000) $PN AL41
J 0
(-7490 3010);
DISPLAY 0.489362 (-7490 3010);
PAINT MONO (-7490 3010);
FORCEPROP 0 LASTPIN (-7500 2950) $PN AP23
J 0
(-7490 2960);
DISPLAY 0.489362 (-7490 2960);
PAINT MONO (-7490 2960);
FORCEPROP 0 LASTPIN (-7500 2900) $PN AP24
J 0
(-7490 2910);
DISPLAY 0.489362 (-7490 2910);
PAINT MONO (-7490 2910);
FORCEPROP 0 LASTPIN (-7500 2850) $PN AP26
J 0
(-7490 2860);
DISPLAY 0.489362 (-7490 2860);
PAINT MONO (-7490 2860);
FORCEPROP 0 LASTPIN (-7500 2800) $PN AP27
J 0
(-7490 2810);
DISPLAY 0.489362 (-7490 2810);
PAINT MONO (-7490 2810);
FORCEPROP 0 LASTPIN (-7500 2750) $PN AP29
J 0
(-7490 2760);
DISPLAY 0.489362 (-7490 2760);
PAINT MONO (-7490 2760);
FORCEPROP 0 LASTPIN (-7500 2700) $PN AP30
J 0
(-7490 2710);
DISPLAY 0.489362 (-7490 2710);
PAINT MONO (-7490 2710);
FORCEPROP 0 LASTPIN (-7500 2650) $PN AP32
J 0
(-7490 2660);
DISPLAY 0.489362 (-7490 2660);
PAINT MONO (-7490 2660);
FORCEPROP 0 LASTPIN (-7500 2600) $PN AP33
J 0
(-7490 2610);
DISPLAY 0.489362 (-7490 2610);
PAINT MONO (-7490 2610);
FORCEPROP 0 LASTPIN (-7500 2550) $PN AP43
J 0
(-7490 2560);
DISPLAY 0.489362 (-7490 2560);
PAINT MONO (-7490 2560);
FORCEPROP 0 LASTPIN (-7500 2500) $PN AP44
J 0
(-7490 2510);
DISPLAY 0.489362 (-7490 2510);
PAINT MONO (-7490 2510);
FORCEPROP 0 LASTPIN (-7500 2450) $PN AP46
J 0
(-7490 2460);
DISPLAY 0.489362 (-7490 2460);
PAINT MONO (-7490 2460);
FORCEPROP 0 LASTPIN (-7500 2400) $PN AP47
J 0
(-7490 2410);
DISPLAY 0.489362 (-7490 2410);
PAINT MONO (-7490 2410);
FORCEPROP 0 LASTPIN (-7500 2350) $PN AP49
J 0
(-7490 2360);
DISPLAY 0.489362 (-7490 2360);
PAINT MONO (-7490 2360);
FORCEPROP 0 LASTPIN (-7500 2300) $PN AP50
J 0
(-7490 2310);
DISPLAY 0.489362 (-7490 2310);
PAINT MONO (-7490 2310);
FORCEPROP 0 LASTPIN (-7500 2250) $PN AP52
J 0
(-7490 2260);
DISPLAY 0.489362 (-7490 2260);
PAINT MONO (-7490 2260);
FORCEPROP 0 LASTPIN (-7500 2200) $PN AP53
J 0
(-7490 2210);
DISPLAY 0.489362 (-7490 2210);
PAINT MONO (-7490 2210);
FORCEPROP 0 LASTPIN (-7500 2150) $PN AR23
J 0
(-7490 2160);
DISPLAY 0.489362 (-7490 2160);
PAINT MONO (-7490 2160);
FORCEPROP 0 LASTPIN (-7500 2100) $PN AR25
J 0
(-7490 2110);
DISPLAY 0.489362 (-7490 2110);
PAINT MONO (-7490 2110);
FORCEPROP 0 LASTPIN (-7500 2050) $PN AR27
J 0
(-7490 2060);
DISPLAY 0.489362 (-7490 2060);
PAINT MONO (-7490 2060);
FORCEPROP 0 LASTPIN (-7500 2000) $PN AR29
J 0
(-7490 2010);
DISPLAY 0.489362 (-7490 2010);
PAINT MONO (-7490 2010);
FORCEPROP 0 LASTPIN (-7500 1950) $PN AR31
J 0
(-7490 1960);
DISPLAY 0.489362 (-7490 1960);
PAINT MONO (-7490 1960);
FORCEPROP 0 LASTPIN (-7500 1900) $PN AR33
J 0
(-7490 1910);
DISPLAY 0.489362 (-7490 1910);
PAINT MONO (-7490 1910);
FORCEPROP 0 LASTPIN (-7500 1850) $PN AR35
J 0
(-7490 1860);
DISPLAY 0.489362 (-7490 1860);
PAINT MONO (-7490 1860);
FORCEPROP 0 LASTPIN (-7500 1800) $PN AR40
J 0
(-7490 1810);
DISPLAY 0.489362 (-7490 1810);
PAINT MONO (-7490 1810);
FORCEPROP 0 LASTPIN (-7500 1750) $PN AR42
J 0
(-7490 1760);
DISPLAY 0.489362 (-7490 1760);
PAINT MONO (-7490 1760);
FORCEPROP 0 LASTPIN (-7500 1700) $PN AR44
J 0
(-7490 1710);
DISPLAY 0.489362 (-7490 1710);
PAINT MONO (-7490 1710);
FORCEPROP 0 LASTPIN (-7500 1650) $PN AR46
J 0
(-7490 1660);
DISPLAY 0.489362 (-7490 1660);
PAINT MONO (-7490 1660);
FORCEPROP 0 LASTPIN (-7500 1600) $PN AR48
J 0
(-7490 1610);
DISPLAY 0.489362 (-7490 1610);
PAINT MONO (-7490 1610);
FORCEPROP 0 LASTPIN (-7500 1550) $PN AR50
J 0
(-7490 1560);
DISPLAY 0.489362 (-7490 1560);
PAINT MONO (-7490 1560);
FORCEPROP 0 LASTPIN (-7500 1500) $PN AT24
J 0
(-7490 1510);
DISPLAY 0.489362 (-7490 1510);
PAINT MONO (-7490 1510);
FORCEPROP 0 LASTPIN (-7500 1450) $PN AT26
J 0
(-7490 1460);
DISPLAY 0.489362 (-7490 1460);
PAINT MONO (-7490 1460);
FORCEPROP 0 LASTPIN (-7500 1400) $PN AT28
J 0
(-7490 1410);
DISPLAY 0.489362 (-7490 1410);
PAINT MONO (-7490 1410);
FORCEPROP 0 LASTPIN (-7500 1350) $PN AT30
J 0
(-7490 1360);
DISPLAY 0.489362 (-7490 1360);
PAINT MONO (-7490 1360);
FORCEPROP 0 LASTPIN (-7500 1300) $PN AT32
J 0
(-7490 1310);
DISPLAY 0.489362 (-7490 1310);
PAINT MONO (-7490 1310);
FORCEPROP 0 LASTPIN (-7500 1250) $PN AT34
J 0
(-7490 1260);
DISPLAY 0.489362 (-7490 1260);
PAINT MONO (-7490 1260);
FORCEPROP 0 LASTPIN (-7500 1200) $PN AT36
J 0
(-7490 1210);
DISPLAY 0.489362 (-7490 1210);
PAINT MONO (-7490 1210);
FORCEPROP 0 LASTPIN (-7500 1150) $PN AT39
J 0
(-7490 1160);
DISPLAY 0.489362 (-7490 1160);
PAINT MONO (-7490 1160);
FORCEPROP 0 LASTPIN (-7500 1100) $PN AT41
J 0
(-7490 1110);
DISPLAY 0.489362 (-7490 1110);
PAINT MONO (-7490 1110);
FORCEPROP 0 LASTPIN (-7500 1050) $PN AT43
J 0
(-7490 1060);
DISPLAY 0.489362 (-7490 1060);
PAINT MONO (-7490 1060);
FORCEPROP 0 LASTPIN (-7500 1000) $PN AT45
J 0
(-7490 1010);
DISPLAY 0.489362 (-7490 1010);
PAINT MONO (-7490 1010);
FORCEPROP 0 LASTPIN (-7500 950) $PN AT47
J 0
(-7490 960);
DISPLAY 0.489362 (-7490 960);
PAINT MONO (-7490 960);
FORCEPROP 0 LASTPIN (-7500 900) $PN AT49
J 0
(-7490 910);
DISPLAY 0.489362 (-7490 910);
PAINT MONO (-7490 910);
FORCEPROP 0 LASTPIN (-7500 600) $PN AU25
J 0
(-7490 610);
DISPLAY 0.489362 (-7490 610);
PAINT MONO (-7490 610);
FORCEPROP 0 LASTPIN (-7500 850) $PN AU29
J 0
(-7490 860);
DISPLAY 0.489362 (-7490 860);
PAINT MONO (-7490 860);
FORCEPROP 0 LASTPIN (-7500 550) $PN AU33
J 0
(-7490 560);
DISPLAY 0.489362 (-7490 560);
PAINT MONO (-7490 560);
FORCEPROP 0 LASTPIN (-7500 800) $PN AU42
J 0
(-7490 810);
DISPLAY 0.489362 (-7490 810);
PAINT MONO (-7490 810);
FORCEPROP 0 LASTPIN (-7500 700) $PN AU44
J 0
(-7490 710);
DISPLAY 0.489362 (-7490 710);
PAINT MONO (-7490 710);
FORCEPROP 0 LASTPIN (-7500 750) $PN AU46
J 0
(-7490 760);
DISPLAY 0.489362 (-7490 760);
PAINT MONO (-7490 760);
FORCEPROP 0 LASTPIN (-7500 650) $PN AU48
J 0
(-7490 660);
DISPLAY 0.489362 (-7490 660);
PAINT MONO (-7490 660);
FORCEPROP 0 LASTPIN (-8800 6350) $PN B19
J 2
(-8810 6360);
DISPLAY 0.489362 (-8810 6360);
PAINT MONO (-8810 6360);
FORCEPROP 0 LASTPIN (-8800 6300) $PN B20
J 2
(-8810 6310);
DISPLAY 0.489362 (-8810 6310);
PAINT MONO (-8810 6310);
FORCEPROP 0 LASTPIN (-8800 6250) $PN B22
J 2
(-8810 6260);
DISPLAY 0.489362 (-8810 6260);
PAINT MONO (-8810 6260);
FORCEPROP 0 LASTPIN (-8800 6200) $PN B23
J 2
(-8810 6210);
DISPLAY 0.489362 (-8810 6210);
PAINT MONO (-8810 6210);
FORCEPROP 0 LASTPIN (-8800 6150) $PN B25
J 2
(-8810 6160);
DISPLAY 0.489362 (-8810 6160);
PAINT MONO (-8810 6160);
FORCEPROP 0 LASTPIN (-8800 6100) $PN B26
J 2
(-8810 6110);
DISPLAY 0.489362 (-8810 6110);
PAINT MONO (-8810 6110);
FORCEPROP 0 LASTPIN (-8800 6050) $PN B28
J 2
(-8810 6060);
DISPLAY 0.489362 (-8810 6060);
PAINT MONO (-8810 6060);
FORCEPROP 0 LASTPIN (-8800 6000) $PN B29
J 2
(-8810 6010);
DISPLAY 0.489362 (-8810 6010);
PAINT MONO (-8810 6010);
FORCEPROP 0 LASTPIN (-8800 5950) $PN B31
J 2
(-8810 5960);
DISPLAY 0.489362 (-8810 5960);
PAINT MONO (-8810 5960);
FORCEPROP 0 LASTPIN (-8800 5900) $PN B32
J 2
(-8810 5910);
DISPLAY 0.489362 (-8810 5910);
PAINT MONO (-8810 5910);
FORCEPROP 0 LASTPIN (-8800 5850) $PN B34
J 2
(-8810 5860);
DISPLAY 0.489362 (-8810 5860);
PAINT MONO (-8810 5860);
FORCEPROP 0 LASTPIN (-8800 5800) $PN B35
J 2
(-8810 5810);
DISPLAY 0.489362 (-8810 5810);
PAINT MONO (-8810 5810);
FORCEPROP 0 LASTPIN (-8800 5750) $PN B41
J 2
(-8810 5760);
DISPLAY 0.489362 (-8810 5760);
PAINT MONO (-8810 5760);
FORCEPROP 0 LASTPIN (-8800 5700) $PN B42
J 2
(-8810 5710);
DISPLAY 0.489362 (-8810 5710);
PAINT MONO (-8810 5710);
FORCEPROP 0 LASTPIN (-8800 5650) $PN B44
J 2
(-8810 5660);
DISPLAY 0.489362 (-8810 5660);
PAINT MONO (-8810 5660);
FORCEPROP 0 LASTPIN (-8800 5600) $PN B45
J 2
(-8810 5610);
DISPLAY 0.489362 (-8810 5610);
PAINT MONO (-8810 5610);
FORCEPROP 0 LASTPIN (-8800 5550) $PN B47
J 2
(-8810 5560);
DISPLAY 0.489362 (-8810 5560);
PAINT MONO (-8810 5560);
FORCEPROP 0 LASTPIN (-8800 5500) $PN B48
J 2
(-8810 5510);
DISPLAY 0.489362 (-8810 5510);
PAINT MONO (-8810 5510);
FORCEPROP 0 LASTPIN (-8800 5450) $PN B50
J 2
(-8810 5460);
DISPLAY 0.489362 (-8810 5460);
PAINT MONO (-8810 5460);
FORCEPROP 0 LASTPIN (-8800 5400) $PN B51
J 2
(-8810 5410);
DISPLAY 0.489362 (-8810 5410);
PAINT MONO (-8810 5410);
FORCEPROP 0 LASTPIN (-8800 5350) $PN B53
J 2
(-8810 5360);
DISPLAY 0.489362 (-8810 5360);
PAINT MONO (-8810 5360);
FORCEPROP 0 LASTPIN (-8800 5300) $PN B54
J 2
(-8810 5310);
DISPLAY 0.489362 (-8810 5310);
PAINT MONO (-8810 5310);
FORCEPROP 0 LASTPIN (-8800 5250) $PN B56
J 2
(-8810 5260);
DISPLAY 0.489362 (-8810 5260);
PAINT MONO (-8810 5260);
FORCEPROP 0 LASTPIN (-8800 5200) $PN B57
J 2
(-8810 5210);
DISPLAY 0.489362 (-8810 5210);
PAINT MONO (-8810 5210);
FORCEPROP 0 LASTPIN (-8800 5150) $PN C20
J 2
(-8810 5160);
DISPLAY 0.489362 (-8810 5160);
PAINT MONO (-8810 5160);
FORCEPROP 0 LASTPIN (-8800 5100) $PN D55
J 2
(-8810 5110);
DISPLAY 0.489362 (-8810 5110);
PAINT MONO (-8810 5110);
FORCEPROP 0 LASTPIN (-8800 5050) $PN D56
J 2
(-8810 5060);
DISPLAY 0.489362 (-8810 5060);
PAINT MONO (-8810 5060);
FORCEPROP 0 LASTPIN (-8800 5000) $PN E22
J 2
(-8810 5010);
DISPLAY 0.489362 (-8810 5010);
PAINT MONO (-8810 5010);
FORCEPROP 0 LASTPIN (-8800 4950) $PN E25
J 2
(-8810 4960);
DISPLAY 0.489362 (-8810 4960);
PAINT MONO (-8810 4960);
FORCEPROP 0 LASTPIN (-8800 4900) $PN E28
J 2
(-8810 4910);
DISPLAY 0.489362 (-8810 4910);
PAINT MONO (-8810 4910);
FORCEPROP 0 LASTPIN (-8800 4850) $PN E31
J 2
(-8810 4860);
DISPLAY 0.489362 (-8810 4860);
PAINT MONO (-8810 4860);
FORCEPROP 0 LASTPIN (-8800 4800) $PN E34
J 2
(-8810 4810);
DISPLAY 0.489362 (-8810 4810);
PAINT MONO (-8810 4810);
FORCEPROP 0 LASTPIN (-8800 4750) $PN E35
J 2
(-8810 4760);
DISPLAY 0.489362 (-8810 4760);
PAINT MONO (-8810 4760);
FORCEPROP 0 LASTPIN (-8800 4700) $PN E42
J 2
(-8810 4710);
DISPLAY 0.489362 (-8810 4710);
PAINT MONO (-8810 4710);
FORCEPROP 0 LASTPIN (-8800 4650) $PN E45
J 2
(-8810 4660);
DISPLAY 0.489362 (-8810 4660);
PAINT MONO (-8810 4660);
FORCEPROP 0 LASTPIN (-8800 4600) $PN E48
J 2
(-8810 4610);
DISPLAY 0.489362 (-8810 4610);
PAINT MONO (-8810 4610);
FORCEPROP 0 LASTPIN (-8800 4550) $PN E51
J 2
(-8810 4560);
DISPLAY 0.489362 (-8810 4560);
PAINT MONO (-8810 4560);
FORCEPROP 0 LASTPIN (-8800 4500) $PN E54
J 2
(-8810 4510);
DISPLAY 0.489362 (-8810 4510);
PAINT MONO (-8810 4510);
FORCEPROP 0 LASTPIN (-8800 4450) $PN F22
J 2
(-8810 4460);
DISPLAY 0.489362 (-8810 4460);
PAINT MONO (-8810 4460);
FORCEPROP 0 LASTPIN (-8800 4400) $PN F25
J 2
(-8810 4410);
DISPLAY 0.489362 (-8810 4410);
PAINT MONO (-8810 4410);
FORCEPROP 0 LASTPIN (-8800 4350) $PN F28
J 2
(-8810 4360);
DISPLAY 0.489362 (-8810 4360);
PAINT MONO (-8810 4360);
FORCEPROP 0 LASTPIN (-8800 4300) $PN F31
J 2
(-8810 4310);
DISPLAY 0.489362 (-8810 4310);
PAINT MONO (-8810 4310);
FORCEPROP 0 LASTPIN (-8800 4250) $PN F34
J 2
(-8810 4260);
DISPLAY 0.489362 (-8810 4260);
PAINT MONO (-8810 4260);
FORCEPROP 0 LASTPIN (-8800 4200) $PN F42
J 2
(-8810 4210);
DISPLAY 0.489362 (-8810 4210);
PAINT MONO (-8810 4210);
FORCEPROP 0 LASTPIN (-8800 4150) $PN F45
J 2
(-8810 4160);
DISPLAY 0.489362 (-8810 4160);
PAINT MONO (-8810 4160);
FORCEPROP 0 LASTPIN (-8800 4100) $PN F48
J 2
(-8810 4110);
DISPLAY 0.489362 (-8810 4110);
PAINT MONO (-8810 4110);
FORCEPROP 0 LASTPIN (-8800 4050) $PN F51
J 2
(-8810 4060);
DISPLAY 0.489362 (-8810 4060);
PAINT MONO (-8810 4060);
FORCEPROP 0 LASTPIN (-8800 4000) $PN F54
J 2
(-8810 4010);
DISPLAY 0.489362 (-8810 4010);
PAINT MONO (-8810 4010);
FORCEPROP 0 LASTPIN (-8800 3950) $PN G35
J 2
(-8810 3960);
DISPLAY 0.489362 (-8810 3960);
PAINT MONO (-8810 3960);
FORCEPROP 0 LASTPIN (-8800 3900) $PN G36
J 2
(-8810 3910);
DISPLAY 0.489362 (-8810 3910);
PAINT MONO (-8810 3910);
FORCEPROP 0 LASTPIN (-8800 3850) $PN G40
J 2
(-8810 3860);
DISPLAY 0.489362 (-8810 3860);
PAINT MONO (-8810 3860);
FORCEPROP 0 LASTPIN (-8800 3800) $PN G41
J 2
(-8810 3810);
DISPLAY 0.489362 (-8810 3810);
PAINT MONO (-8810 3810);
FORCEPROP 0 LASTPIN (-8800 3750) $PN H23
J 2
(-8810 3760);
DISPLAY 0.489362 (-8810 3760);
PAINT MONO (-8810 3760);
FORCEPROP 0 LASTPIN (-8800 3700) $PN H24
J 2
(-8810 3710);
DISPLAY 0.489362 (-8810 3710);
PAINT MONO (-8810 3710);
FORCEPROP 0 LASTPIN (-8800 3650) $PN H26
J 2
(-8810 3660);
DISPLAY 0.489362 (-8810 3660);
PAINT MONO (-8810 3660);
FORCEPROP 0 LASTPIN (-8800 3600) $PN H27
J 2
(-8810 3610);
DISPLAY 0.489362 (-8810 3610);
PAINT MONO (-8810 3610);
FORCEPROP 0 LASTPIN (-8800 3550) $PN H29
J 2
(-8810 3560);
DISPLAY 0.489362 (-8810 3560);
PAINT MONO (-8810 3560);
FORCEPROP 0 LASTPIN (-8800 3500) $PN H30
J 2
(-8810 3510);
DISPLAY 0.489362 (-8810 3510);
PAINT MONO (-8810 3510);
FORCEPROP 0 LASTPIN (-8800 3450) $PN H32
J 2
(-8810 3460);
DISPLAY 0.489362 (-8810 3460);
PAINT MONO (-8810 3460);
FORCEPROP 0 LASTPIN (-8800 3400) $PN H33
J 2
(-8810 3410);
DISPLAY 0.489362 (-8810 3410);
PAINT MONO (-8810 3410);
FORCEPROP 0 LASTPIN (-8800 3350) $PN H43
J 2
(-8810 3360);
DISPLAY 0.489362 (-8810 3360);
PAINT MONO (-8810 3360);
FORCEPROP 0 LASTPIN (-8800 3300) $PN H44
J 2
(-8810 3310);
DISPLAY 0.489362 (-8810 3310);
PAINT MONO (-8810 3310);
FORCEPROP 0 LASTPIN (-8800 3250) $PN H46
J 2
(-8810 3260);
DISPLAY 0.489362 (-8810 3260);
PAINT MONO (-8810 3260);
FORCEPROP 0 LASTPIN (-8800 3200) $PN H47
J 2
(-8810 3210);
DISPLAY 0.489362 (-8810 3210);
PAINT MONO (-8810 3210);
FORCEPROP 0 LASTPIN (-8800 3150) $PN H49
J 2
(-8810 3160);
DISPLAY 0.489362 (-8810 3160);
PAINT MONO (-8810 3160);
FORCEPROP 0 LASTPIN (-8800 3100) $PN H50
J 2
(-8810 3110);
DISPLAY 0.489362 (-8810 3110);
PAINT MONO (-8810 3110);
FORCEPROP 0 LASTPIN (-8800 3050) $PN H52
J 2
(-8810 3060);
DISPLAY 0.489362 (-8810 3060);
PAINT MONO (-8810 3060);
FORCEPROP 0 LASTPIN (-8800 3000) $PN H53
J 2
(-8810 3010);
DISPLAY 0.489362 (-8810 3010);
PAINT MONO (-8810 3010);
FORCEPROP 0 LASTPIN (-8800 2950) $PN J35
J 2
(-8810 2960);
DISPLAY 0.489362 (-8810 2960);
PAINT MONO (-8810 2960);
FORCEPROP 0 LASTPIN (-8800 2900) $PN J36
J 2
(-8810 2910);
DISPLAY 0.489362 (-8810 2910);
PAINT MONO (-8810 2910);
FORCEPROP 0 LASTPIN (-8800 2850) $PN J40
J 2
(-8810 2860);
DISPLAY 0.489362 (-8810 2860);
PAINT MONO (-8810 2860);
FORCEPROP 0 LASTPIN (-8800 2800) $PN J41
J 2
(-8810 2810);
DISPLAY 0.489362 (-8810 2810);
PAINT MONO (-8810 2810);
FORCEPROP 0 LASTPIN (-8800 2750) $PN M23
J 2
(-8810 2760);
DISPLAY 0.489362 (-8810 2760);
PAINT MONO (-8810 2760);
FORCEPROP 0 LASTPIN (-8800 2700) $PN M24
J 2
(-8810 2710);
DISPLAY 0.489362 (-8810 2710);
PAINT MONO (-8810 2710);
FORCEPROP 0 LASTPIN (-8800 2650) $PN M26
J 2
(-8810 2660);
DISPLAY 0.489362 (-8810 2660);
PAINT MONO (-8810 2660);
FORCEPROP 0 LASTPIN (-8800 2600) $PN M27
J 2
(-8810 2610);
DISPLAY 0.489362 (-8810 2610);
PAINT MONO (-8810 2610);
FORCEPROP 0 LASTPIN (-8800 2550) $PN M29
J 2
(-8810 2560);
DISPLAY 0.489362 (-8810 2560);
PAINT MONO (-8810 2560);
FORCEPROP 0 LASTPIN (-8800 2500) $PN M30
J 2
(-8810 2510);
DISPLAY 0.489362 (-8810 2510);
PAINT MONO (-8810 2510);
FORCEPROP 0 LASTPIN (-8800 2450) $PN M32
J 2
(-8810 2460);
DISPLAY 0.489362 (-8810 2460);
PAINT MONO (-8810 2460);
FORCEPROP 0 LASTPIN (-8800 2400) $PN M33
J 2
(-8810 2410);
DISPLAY 0.489362 (-8810 2410);
PAINT MONO (-8810 2410);
FORCEPROP 0 LASTPIN (-8800 2350) $PN M43
J 2
(-8810 2360);
DISPLAY 0.489362 (-8810 2360);
PAINT MONO (-8810 2360);
FORCEPROP 0 LASTPIN (-8800 2300) $PN M44
J 2
(-8810 2310);
DISPLAY 0.489362 (-8810 2310);
PAINT MONO (-8810 2310);
FORCEPROP 0 LASTPIN (-8800 2250) $PN M46
J 2
(-8810 2260);
DISPLAY 0.489362 (-8810 2260);
PAINT MONO (-8810 2260);
FORCEPROP 0 LASTPIN (-8800 2200) $PN M47
J 2
(-8810 2210);
DISPLAY 0.489362 (-8810 2210);
PAINT MONO (-8810 2210);
FORCEPROP 0 LASTPIN (-8800 2150) $PN M49
J 2
(-8810 2160);
DISPLAY 0.489362 (-8810 2160);
PAINT MONO (-8810 2160);
FORCEPROP 0 LASTPIN (-8800 2100) $PN M50
J 2
(-8810 2110);
DISPLAY 0.489362 (-8810 2110);
PAINT MONO (-8810 2110);
FORCEPROP 0 LASTPIN (-8800 2050) $PN M52
J 2
(-8810 2060);
DISPLAY 0.489362 (-8810 2060);
PAINT MONO (-8810 2060);
FORCEPROP 0 LASTPIN (-8800 2000) $PN M53
J 2
(-8810 2010);
DISPLAY 0.489362 (-8810 2010);
PAINT MONO (-8810 2010);
FORCEPROP 0 LASTPIN (-8800 1950) $PN N35
J 2
(-8810 1960);
DISPLAY 0.489362 (-8810 1960);
PAINT MONO (-8810 1960);
FORCEPROP 0 LASTPIN (-8800 1900) $PN N36
J 2
(-8810 1910);
DISPLAY 0.489362 (-8810 1910);
PAINT MONO (-8810 1910);
FORCEPROP 0 LASTPIN (-8800 1850) $PN N40
J 2
(-8810 1860);
DISPLAY 0.489362 (-8810 1860);
PAINT MONO (-8810 1860);
FORCEPROP 0 LASTPIN (-8800 1800) $PN N41
J 2
(-8810 1810);
DISPLAY 0.489362 (-8810 1810);
PAINT MONO (-8810 1810);
FORCEPROP 0 LASTPIN (-8800 1750) $PN T23
J 2
(-8810 1760);
DISPLAY 0.489362 (-8810 1760);
PAINT MONO (-8810 1760);
FORCEPROP 0 LASTPIN (-8800 1700) $PN T24
J 2
(-8810 1710);
DISPLAY 0.489362 (-8810 1710);
PAINT MONO (-8810 1710);
FORCEPROP 0 LASTPIN (-8800 1650) $PN T26
J 2
(-8810 1660);
DISPLAY 0.489362 (-8810 1660);
PAINT MONO (-8810 1660);
FORCEPROP 0 LASTPIN (-8800 1600) $PN T27
J 2
(-8810 1610);
DISPLAY 0.489362 (-8810 1610);
PAINT MONO (-8810 1610);
FORCEPROP 0 LASTPIN (-8800 1550) $PN T29
J 2
(-8810 1560);
DISPLAY 0.489362 (-8810 1560);
PAINT MONO (-8810 1560);
FORCEPROP 0 LASTPIN (-8800 1500) $PN T30
J 2
(-8810 1510);
DISPLAY 0.489362 (-8810 1510);
PAINT MONO (-8810 1510);
FORCEPROP 0 LASTPIN (-8800 1450) $PN T32
J 2
(-8810 1460);
DISPLAY 0.489362 (-8810 1460);
PAINT MONO (-8810 1460);
FORCEPROP 0 LASTPIN (-8800 1400) $PN T33
J 2
(-8810 1410);
DISPLAY 0.489362 (-8810 1410);
PAINT MONO (-8810 1410);
FORCEPROP 0 LASTPIN (-8800 1350) $PN T43
J 2
(-8810 1360);
DISPLAY 0.489362 (-8810 1360);
PAINT MONO (-8810 1360);
FORCEPROP 0 LASTPIN (-8800 1300) $PN T44
J 2
(-8810 1310);
DISPLAY 0.489362 (-8810 1310);
PAINT MONO (-8810 1310);
FORCEPROP 0 LASTPIN (-8800 1250) $PN T46
J 2
(-8810 1260);
DISPLAY 0.489362 (-8810 1260);
PAINT MONO (-8810 1260);
FORCEPROP 0 LASTPIN (-8800 1200) $PN T47
J 2
(-8810 1210);
DISPLAY 0.489362 (-8810 1210);
PAINT MONO (-8810 1210);
FORCEPROP 0 LASTPIN (-8800 1150) $PN T49
J 2
(-8810 1160);
DISPLAY 0.489362 (-8810 1160);
PAINT MONO (-8810 1160);
FORCEPROP 0 LASTPIN (-8800 1100) $PN T50
J 2
(-8810 1110);
DISPLAY 0.489362 (-8810 1110);
PAINT MONO (-8810 1110);
FORCEPROP 0 LASTPIN (-8800 1050) $PN T52
J 2
(-8810 1060);
DISPLAY 0.489362 (-8810 1060);
PAINT MONO (-8810 1060);
FORCEPROP 0 LASTPIN (-8800 1000) $PN T53
J 2
(-8810 1010);
DISPLAY 0.489362 (-8810 1010);
PAINT MONO (-8810 1010);
FORCEPROP 0 LASTPIN (-8800 950) $PN U35
J 2
(-8810 960);
DISPLAY 0.489362 (-8810 960);
PAINT MONO (-8810 960);
FORCEPROP 0 LASTPIN (-8800 900) $PN U36
J 2
(-8810 910);
DISPLAY 0.489362 (-8810 910);
PAINT MONO (-8810 910);
FORCEPROP 0 LASTPIN (-8800 850) $PN U40
J 2
(-8810 860);
DISPLAY 0.489362 (-8810 860);
PAINT MONO (-8810 860);
FORCEPROP 0 LASTPIN (-8800 800) $PN U41
J 2
(-8810 810);
DISPLAY 0.489362 (-8810 810);
PAINT MONO (-8810 810);
FORCEPROP 0 LASTPIN (-8800 750) $PN W29
J 2
(-8810 760);
DISPLAY 0.489362 (-8810 760);
PAINT MONO (-8810 760);
FORCEPROP 0 LASTPIN (-8800 700) $PN W30
J 2
(-8810 710);
DISPLAY 0.489362 (-8810 710);
PAINT MONO (-8810 710);
FORCEPROP 0 LASTPIN (-8800 650) $PN W32
J 2
(-8810 660);
DISPLAY 0.489362 (-8810 660);
PAINT MONO (-8810 660);
FORCEPROP 0 LASTPIN (-8800 600) $PN W33
J 2
(-8810 610);
DISPLAY 0.489362 (-8810 610);
PAINT MONO (-8810 610);
FORCEPROP 0 LASTPIN (-7500 6350) $PN W43
J 0
(-7490 6360);
DISPLAY 0.489362 (-7490 6360);
PAINT MONO (-7490 6360);
FORCEPROP 0 LASTPIN (-7500 6300) $PN W44
J 0
(-7490 6310);
DISPLAY 0.489362 (-7490 6310);
PAINT MONO (-7490 6310);
FORCEPROP 0 LASTPIN (-7500 6250) $PN W46
J 0
(-7490 6260);
DISPLAY 0.489362 (-7490 6260);
PAINT MONO (-7490 6260);
FORCEPROP 0 LASTPIN (-7500 6200) $PN W47
J 0
(-7490 6210);
DISPLAY 0.489362 (-7490 6210);
PAINT MONO (-7490 6210);
FORCEPROP 0 LASTPIN (-7500 6150) $PN Y35
J 0
(-7490 6160);
DISPLAY 0.489362 (-7490 6160);
PAINT MONO (-7490 6160);
FORCEPROP 0 LASTPIN (-7500 6100) $PN Y36
J 0
(-7490 6110);
DISPLAY 0.489362 (-7490 6110);
PAINT MONO (-7490 6110);
FORCEPROP 0 LASTPIN (-7500 6050) $PN Y40
J 0
(-7490 6060);
DISPLAY 0.489362 (-7490 6060);
PAINT MONO (-7490 6060);
FORCEPROP 0 LASTPIN (-7500 6000) $PN Y41
J 0
(-7490 6010);
DISPLAY 0.489362 (-7490 6010);
PAINT MONO (-7490 6010);
FORCEPROP 2 LAST VALUE SOCKET6096_13568-001
J 0
(-8650 6575);
DISPLAY 0.489362 (-8650 6575);
PAINT SKYBLUE (-8650 6575);
FORCEPROP 2 LAST PART_TYPE SMLF
J 0
(-8650 6675);
DISPLAY 1.021277 (-8650 6675);
FORCEPROP 1 LAST MATERIAL IO
J 0
(-8645 6520);
DISPLAY 0.489362 (-8645 6520);
PAINT SKYBLUE (-8645 6520);
FORCEPROP 1 LAST NEEDS_NO_SIZE TRUE
J 0
(-8150 3350);
DISPLAY 0.723404 (-8150 3350);
PAINT GREEN (-8150 3350);
DISPLAY INVISIBLE (-8150 3350);
FORCEPROP 1 LAST CDS_LMAN_SYM_OUTLINE -500,3150,500,-3150
J 0
(-8150 3350);
DISPLAY 0.468085 (-8150 3350);
PAINT GREEN (-8150 3350);
DISPLAY INVISIBLE (-8150 3350);
FORCEPROP 2 LAST CDS_LIB pure_quanta
J 0
(-8150 3350);
DISPLAY INVISIBLE (-8150 3350);
FORCEPROP 1 LAST PATH I29
J 0
(-8150 3350);
DISPLAY 0.723404 (-8150 3350);
PAINT GREEN (-8150 3350);
DISPLAY INVISIBLE (-8150 3350);
FORCEPROP 1 LAST PART_NUMBER DGA^6000030
J 0
(-8645 6647);
DISPLAY 0.489362 (-8645 6647);
PAINT SKYBLUE (-8645 6647);
DISPLAY INVISIBLE (-8645 6647);
FORCEADD VCC_CORE..1
(-5525 6550);
FORCEPROP 3 LASTPIN (-5525 6500) SIG_NAME PVDDCR_CPU1_P1\g
J 0
(-5515 6510);
DISPLAY 0.659574 (-5515 6510);
PAINT MONO (-5515 6510);
DISPLAY INVISIBLE (-5515 6510);
FORCEPROP 1 LAST HDL_POWER PVDDCR_CPU1_P1
J 1
(-5525 6600);
DISPLAY 0.489362 (-5525 6600);
PAINT GREEN (-5525 6600);
FORCEPROP 2 LAST CDS_LIB pure_quanta_power
J 0
(-5525 6550);
DISPLAY INVISIBLE (-5525 6550);
FORCEPROP 1 LAST PATH I30
J 0
(-5475 6575);
DISPLAY 0.872340 (-5475 6575);
PAINT AQUA (-5475 6575);
DISPLAY INVISIBLE (-5475 6575);
FORCEADD VCC_CORE..1
(-6950 6325);
FORCEPROP 3 LASTPIN (-6950 6275) SIG_NAME PVDDCR_CPU1_P1\g
J 0
(-6940 6285);
DISPLAY 0.659574 (-6940 6285);
PAINT MONO (-6940 6285);
DISPLAY INVISIBLE (-6940 6285);
FORCEPROP 1 LAST HDL_POWER PVDDCR_CPU1_P1
J 1
(-6950 6375);
DISPLAY 0.489362 (-6950 6375);
PAINT GREEN (-6950 6375);
FORCEPROP 2 LAST CDS_LIB pure_quanta_power
J 0
(-6950 6325);
DISPLAY INVISIBLE (-6950 6325);
FORCEPROP 1 LAST PATH I31
J 0
(-6900 6350);
DISPLAY 0.872340 (-6900 6350);
PAINT AQUA (-6900 6350);
DISPLAY INVISIBLE (-6900 6350);
FORCEADD GENOA_SP5..25
(-6225 3375);
FORCEPROP 1 LAST LOCATION U26
J 0
(-6725 6675);
DISPLAY 0.489362 (-6725 6675);
PAINT SKYBLUE (-6725 6675);
FORCEPROP 0 LAST $SEC 25
J 0
(-6700 6925);
DISPLAY 0.680851 (-6700 6925);
PAINT MONO (-6700 6925);
DISPLAY INVISIBLE (-6700 6925);
FORCEPROP 0 LAST CDS_SEC 25
J 0
(-6700 6925);
DISPLAY 1.021277 (-6700 6925);
DISPLAY INVISIBLE (-6700 6925);
FORCEPROP 0 LASTPIN (-5575 525) $PN BN27
J 0
(-5565 535);
DISPLAY 0.489362 (-5565 535);
PAINT MONO (-5565 535);
FORCEPROP 0 LASTPIN (-6875 6125) $PN BN31
J 2
(-6885 6135);
DISPLAY 0.489362 (-6885 6135);
PAINT MONO (-6885 6135);
FORCEPROP 0 LASTPIN (-5575 475) $PN BN35
J 0
(-5565 485);
DISPLAY 0.489362 (-5565 485);
PAINT MONO (-5565 485);
FORCEPROP 0 LASTPIN (-6875 6075) $PN BN42
J 2
(-6885 6085);
DISPLAY 0.489362 (-6885 6085);
PAINT MONO (-6885 6085);
FORCEPROP 0 LASTPIN (-5575 425) $PN BN46
J 0
(-5565 435);
DISPLAY 0.489362 (-5565 435);
PAINT MONO (-5565 435);
FORCEPROP 0 LASTPIN (-6875 6025) $PN BN50
J 2
(-6885 6035);
DISPLAY 0.489362 (-6885 6035);
PAINT MONO (-6885 6035);
FORCEPROP 0 LASTPIN (-5575 375) $PN BP24
J 0
(-5565 385);
DISPLAY 0.489362 (-5565 385);
PAINT MONO (-5565 385);
FORCEPROP 0 LASTPIN (-6875 5975) $PN BP26
J 2
(-6885 5985);
DISPLAY 0.489362 (-6885 5985);
PAINT MONO (-6885 5985);
FORCEPROP 0 LASTPIN (-5575 325) $PN BP28
J 0
(-5565 335);
DISPLAY 0.489362 (-5565 335);
PAINT MONO (-5565 335);
FORCEPROP 0 LASTPIN (-6875 5925) $PN BP30
J 2
(-6885 5935);
DISPLAY 0.489362 (-6885 5935);
PAINT MONO (-6885 5935);
FORCEPROP 0 LASTPIN (-5575 275) $PN BP32
J 0
(-5565 285);
DISPLAY 0.489362 (-5565 285);
PAINT MONO (-5565 285);
FORCEPROP 0 LASTPIN (-6875 5875) $PN BP34
J 2
(-6885 5885);
DISPLAY 0.489362 (-6885 5885);
PAINT MONO (-6885 5885);
FORCEPROP 0 LASTPIN (-6875 5825) $PN BP36
J 2
(-6885 5835);
DISPLAY 0.489362 (-6885 5835);
PAINT MONO (-6885 5835);
FORCEPROP 0 LASTPIN (-6875 5775) $PN BP39
J 2
(-6885 5785);
DISPLAY 0.489362 (-6885 5785);
PAINT MONO (-6885 5785);
FORCEPROP 0 LASTPIN (-6875 5725) $PN BP41
J 2
(-6885 5735);
DISPLAY 0.489362 (-6885 5735);
PAINT MONO (-6885 5735);
FORCEPROP 0 LASTPIN (-6875 5675) $PN BP43
J 2
(-6885 5685);
DISPLAY 0.489362 (-6885 5685);
PAINT MONO (-6885 5685);
FORCEPROP 0 LASTPIN (-6875 5625) $PN BP45
J 2
(-6885 5635);
DISPLAY 0.489362 (-6885 5635);
PAINT MONO (-6885 5635);
FORCEPROP 0 LASTPIN (-6875 5575) $PN BP47
J 2
(-6885 5585);
DISPLAY 0.489362 (-6885 5585);
PAINT MONO (-6885 5585);
FORCEPROP 0 LASTPIN (-6875 5525) $PN BP49
J 2
(-6885 5535);
DISPLAY 0.489362 (-6885 5535);
PAINT MONO (-6885 5535);
FORCEPROP 0 LASTPIN (-6875 5475) $PN BR23
J 2
(-6885 5485);
DISPLAY 0.489362 (-6885 5485);
PAINT MONO (-6885 5485);
FORCEPROP 0 LASTPIN (-6875 5425) $PN BR25
J 2
(-6885 5435);
DISPLAY 0.489362 (-6885 5435);
PAINT MONO (-6885 5435);
FORCEPROP 0 LASTPIN (-6875 5375) $PN BR27
J 2
(-6885 5385);
DISPLAY 0.489362 (-6885 5385);
PAINT MONO (-6885 5385);
FORCEPROP 0 LASTPIN (-6875 5325) $PN BR29
J 2
(-6885 5335);
DISPLAY 0.489362 (-6885 5335);
PAINT MONO (-6885 5335);
FORCEPROP 0 LASTPIN (-6875 5275) $PN BR31
J 2
(-6885 5285);
DISPLAY 0.489362 (-6885 5285);
PAINT MONO (-6885 5285);
FORCEPROP 0 LASTPIN (-6875 5225) $PN BR33
J 2
(-6885 5235);
DISPLAY 0.489362 (-6885 5235);
PAINT MONO (-6885 5235);
FORCEPROP 0 LASTPIN (-6875 5175) $PN BR35
J 2
(-6885 5185);
DISPLAY 0.489362 (-6885 5185);
PAINT MONO (-6885 5185);
FORCEPROP 0 LASTPIN (-6875 5125) $PN BR40
J 2
(-6885 5135);
DISPLAY 0.489362 (-6885 5135);
PAINT MONO (-6885 5135);
FORCEPROP 0 LASTPIN (-6875 5075) $PN BR42
J 2
(-6885 5085);
DISPLAY 0.489362 (-6885 5085);
PAINT MONO (-6885 5085);
FORCEPROP 0 LASTPIN (-6875 5025) $PN BR44
J 2
(-6885 5035);
DISPLAY 0.489362 (-6885 5035);
PAINT MONO (-6885 5035);
FORCEPROP 0 LASTPIN (-6875 4975) $PN BR46
J 2
(-6885 4985);
DISPLAY 0.489362 (-6885 4985);
PAINT MONO (-6885 4985);
FORCEPROP 0 LASTPIN (-6875 4925) $PN BR48
J 2
(-6885 4935);
DISPLAY 0.489362 (-6885 4935);
PAINT MONO (-6885 4935);
FORCEPROP 0 LASTPIN (-6875 4875) $PN BR50
J 2
(-6885 4885);
DISPLAY 0.489362 (-6885 4885);
PAINT MONO (-6885 4885);
FORCEPROP 0 LASTPIN (-6875 4825) $PN BR52
J 2
(-6885 4835);
DISPLAY 0.489362 (-6885 4835);
PAINT MONO (-6885 4835);
FORCEPROP 0 LASTPIN (-6875 4775) $PN BT23
J 2
(-6885 4785);
DISPLAY 0.489362 (-6885 4785);
PAINT MONO (-6885 4785);
FORCEPROP 0 LASTPIN (-6875 4725) $PN BT24
J 2
(-6885 4735);
DISPLAY 0.489362 (-6885 4735);
PAINT MONO (-6885 4735);
FORCEPROP 0 LASTPIN (-6875 4675) $PN BT26
J 2
(-6885 4685);
DISPLAY 0.489362 (-6885 4685);
PAINT MONO (-6885 4685);
FORCEPROP 0 LASTPIN (-6875 4625) $PN BT27
J 2
(-6885 4635);
DISPLAY 0.489362 (-6885 4635);
PAINT MONO (-6885 4635);
FORCEPROP 0 LASTPIN (-6875 4575) $PN BT29
J 2
(-6885 4585);
DISPLAY 0.489362 (-6885 4585);
PAINT MONO (-6885 4585);
FORCEPROP 0 LASTPIN (-6875 4525) $PN BT30
J 2
(-6885 4535);
DISPLAY 0.489362 (-6885 4535);
PAINT MONO (-6885 4535);
FORCEPROP 0 LASTPIN (-6875 4475) $PN BT32
J 2
(-6885 4485);
DISPLAY 0.489362 (-6885 4485);
PAINT MONO (-6885 4485);
FORCEPROP 0 LASTPIN (-6875 4425) $PN BT33
J 2
(-6885 4435);
DISPLAY 0.489362 (-6885 4435);
PAINT MONO (-6885 4435);
FORCEPROP 0 LASTPIN (-6875 4375) $PN BT43
J 2
(-6885 4385);
DISPLAY 0.489362 (-6885 4385);
PAINT MONO (-6885 4385);
FORCEPROP 0 LASTPIN (-6875 4325) $PN BT44
J 2
(-6885 4335);
DISPLAY 0.489362 (-6885 4335);
PAINT MONO (-6885 4335);
FORCEPROP 0 LASTPIN (-6875 4275) $PN BT46
J 2
(-6885 4285);
DISPLAY 0.489362 (-6885 4285);
PAINT MONO (-6885 4285);
FORCEPROP 0 LASTPIN (-6875 4225) $PN BT47
J 2
(-6885 4235);
DISPLAY 0.489362 (-6885 4235);
PAINT MONO (-6885 4235);
FORCEPROP 0 LASTPIN (-6875 4175) $PN BT49
J 2
(-6885 4185);
DISPLAY 0.489362 (-6885 4185);
PAINT MONO (-6885 4185);
FORCEPROP 0 LASTPIN (-6875 4125) $PN BT50
J 2
(-6885 4135);
DISPLAY 0.489362 (-6885 4135);
PAINT MONO (-6885 4135);
FORCEPROP 0 LASTPIN (-6875 4075) $PN BT52
J 2
(-6885 4085);
DISPLAY 0.489362 (-6885 4085);
PAINT MONO (-6885 4085);
FORCEPROP 0 LASTPIN (-6875 4025) $PN BT53
J 2
(-6885 4035);
DISPLAY 0.489362 (-6885 4035);
PAINT MONO (-6885 4035);
FORCEPROP 0 LASTPIN (-6875 3975) $PN BW35
J 2
(-6885 3985);
DISPLAY 0.489362 (-6885 3985);
PAINT MONO (-6885 3985);
FORCEPROP 0 LASTPIN (-6875 3925) $PN BW36
J 2
(-6885 3935);
DISPLAY 0.489362 (-6885 3935);
PAINT MONO (-6885 3935);
FORCEPROP 0 LASTPIN (-6875 3875) $PN BW40
J 2
(-6885 3885);
DISPLAY 0.489362 (-6885 3885);
PAINT MONO (-6885 3885);
FORCEPROP 0 LASTPIN (-6875 3825) $PN BW41
J 2
(-6885 3835);
DISPLAY 0.489362 (-6885 3835);
PAINT MONO (-6885 3835);
FORCEPROP 0 LASTPIN (-6875 3775) $PN BY23
J 2
(-6885 3785);
DISPLAY 0.489362 (-6885 3785);
PAINT MONO (-6885 3785);
FORCEPROP 0 LASTPIN (-6875 3725) $PN BY24
J 2
(-6885 3735);
DISPLAY 0.489362 (-6885 3735);
PAINT MONO (-6885 3735);
FORCEPROP 0 LASTPIN (-6875 3675) $PN BY26
J 2
(-6885 3685);
DISPLAY 0.489362 (-6885 3685);
PAINT MONO (-6885 3685);
FORCEPROP 0 LASTPIN (-6875 3625) $PN BY27
J 2
(-6885 3635);
DISPLAY 0.489362 (-6885 3635);
PAINT MONO (-6885 3635);
FORCEPROP 0 LASTPIN (-6875 3575) $PN BY29
J 2
(-6885 3585);
DISPLAY 0.489362 (-6885 3585);
PAINT MONO (-6885 3585);
FORCEPROP 0 LASTPIN (-6875 3525) $PN BY30
J 2
(-6885 3535);
DISPLAY 0.489362 (-6885 3535);
PAINT MONO (-6885 3535);
FORCEPROP 0 LASTPIN (-6875 3475) $PN BY32
J 2
(-6885 3485);
DISPLAY 0.489362 (-6885 3485);
PAINT MONO (-6885 3485);
FORCEPROP 0 LASTPIN (-6875 3425) $PN BY33
J 2
(-6885 3435);
DISPLAY 0.489362 (-6885 3435);
PAINT MONO (-6885 3435);
FORCEPROP 0 LASTPIN (-6875 3375) $PN BY43
J 2
(-6885 3385);
DISPLAY 0.489362 (-6885 3385);
PAINT MONO (-6885 3385);
FORCEPROP 0 LASTPIN (-6875 3325) $PN BY44
J 2
(-6885 3335);
DISPLAY 0.489362 (-6885 3335);
PAINT MONO (-6885 3335);
FORCEPROP 0 LASTPIN (-6875 3275) $PN BY46
J 2
(-6885 3285);
DISPLAY 0.489362 (-6885 3285);
PAINT MONO (-6885 3285);
FORCEPROP 0 LASTPIN (-6875 3225) $PN BY47
J 2
(-6885 3235);
DISPLAY 0.489362 (-6885 3235);
PAINT MONO (-6885 3235);
FORCEPROP 0 LASTPIN (-6875 3175) $PN BY49
J 2
(-6885 3185);
DISPLAY 0.489362 (-6885 3185);
PAINT MONO (-6885 3185);
FORCEPROP 0 LASTPIN (-6875 3125) $PN BY50
J 2
(-6885 3135);
DISPLAY 0.489362 (-6885 3135);
PAINT MONO (-6885 3135);
FORCEPROP 0 LASTPIN (-6875 3075) $PN BY52
J 2
(-6885 3085);
DISPLAY 0.489362 (-6885 3085);
PAINT MONO (-6885 3085);
FORCEPROP 0 LASTPIN (-6875 3025) $PN BY53
J 2
(-6885 3035);
DISPLAY 0.489362 (-6885 3035);
PAINT MONO (-6885 3035);
FORCEPROP 0 LASTPIN (-6875 2975) $PN CC35
J 2
(-6885 2985);
DISPLAY 0.489362 (-6885 2985);
PAINT MONO (-6885 2985);
FORCEPROP 0 LASTPIN (-6875 2925) $PN CC36
J 2
(-6885 2935);
DISPLAY 0.489362 (-6885 2935);
PAINT MONO (-6885 2935);
FORCEPROP 0 LASTPIN (-6875 2875) $PN CC40
J 2
(-6885 2885);
DISPLAY 0.489362 (-6885 2885);
PAINT MONO (-6885 2885);
FORCEPROP 0 LASTPIN (-6875 2825) $PN CC41
J 2
(-6885 2835);
DISPLAY 0.489362 (-6885 2835);
PAINT MONO (-6885 2835);
FORCEPROP 0 LASTPIN (-6875 2775) $PN CD23
J 2
(-6885 2785);
DISPLAY 0.489362 (-6885 2785);
PAINT MONO (-6885 2785);
FORCEPROP 0 LASTPIN (-6875 2725) $PN CD24
J 2
(-6885 2735);
DISPLAY 0.489362 (-6885 2735);
PAINT MONO (-6885 2735);
FORCEPROP 0 LASTPIN (-6875 2675) $PN CD26
J 2
(-6885 2685);
DISPLAY 0.489362 (-6885 2685);
PAINT MONO (-6885 2685);
FORCEPROP 0 LASTPIN (-6875 2625) $PN CD27
J 2
(-6885 2635);
DISPLAY 0.489362 (-6885 2635);
PAINT MONO (-6885 2635);
FORCEPROP 0 LASTPIN (-6875 2575) $PN CD29
J 2
(-6885 2585);
DISPLAY 0.489362 (-6885 2585);
PAINT MONO (-6885 2585);
FORCEPROP 0 LASTPIN (-6875 2525) $PN CD30
J 2
(-6885 2535);
DISPLAY 0.489362 (-6885 2535);
PAINT MONO (-6885 2535);
FORCEPROP 0 LASTPIN (-6875 2475) $PN CD32
J 2
(-6885 2485);
DISPLAY 0.489362 (-6885 2485);
PAINT MONO (-6885 2485);
FORCEPROP 0 LASTPIN (-6875 2425) $PN CD33
J 2
(-6885 2435);
DISPLAY 0.489362 (-6885 2435);
PAINT MONO (-6885 2435);
FORCEPROP 0 LASTPIN (-6875 2375) $PN CD43
J 2
(-6885 2385);
DISPLAY 0.489362 (-6885 2385);
PAINT MONO (-6885 2385);
FORCEPROP 0 LASTPIN (-6875 2325) $PN CD44
J 2
(-6885 2335);
DISPLAY 0.489362 (-6885 2335);
PAINT MONO (-6885 2335);
FORCEPROP 0 LASTPIN (-6875 2275) $PN CD46
J 2
(-6885 2285);
DISPLAY 0.489362 (-6885 2285);
PAINT MONO (-6885 2285);
FORCEPROP 0 LASTPIN (-6875 2225) $PN CD47
J 2
(-6885 2235);
DISPLAY 0.489362 (-6885 2235);
PAINT MONO (-6885 2235);
FORCEPROP 0 LASTPIN (-6875 2175) $PN CD49
J 2
(-6885 2185);
DISPLAY 0.489362 (-6885 2185);
PAINT MONO (-6885 2185);
FORCEPROP 0 LASTPIN (-6875 2125) $PN CD50
J 2
(-6885 2135);
DISPLAY 0.489362 (-6885 2135);
PAINT MONO (-6885 2135);
FORCEPROP 0 LASTPIN (-6875 2075) $PN CD52
J 2
(-6885 2085);
DISPLAY 0.489362 (-6885 2085);
PAINT MONO (-6885 2085);
FORCEPROP 0 LASTPIN (-6875 2025) $PN CD53
J 2
(-6885 2035);
DISPLAY 0.489362 (-6885 2035);
PAINT MONO (-6885 2035);
FORCEPROP 0 LASTPIN (-6875 1975) $PN CG35
J 2
(-6885 1985);
DISPLAY 0.489362 (-6885 1985);
PAINT MONO (-6885 1985);
FORCEPROP 0 LASTPIN (-6875 1925) $PN CG36
J 2
(-6885 1935);
DISPLAY 0.489362 (-6885 1935);
PAINT MONO (-6885 1935);
FORCEPROP 0 LASTPIN (-6875 1875) $PN CG40
J 2
(-6885 1885);
DISPLAY 0.489362 (-6885 1885);
PAINT MONO (-6885 1885);
FORCEPROP 0 LASTPIN (-6875 1825) $PN CG41
J 2
(-6885 1835);
DISPLAY 0.489362 (-6885 1835);
PAINT MONO (-6885 1835);
FORCEPROP 0 LASTPIN (-6875 1775) $PN CH23
J 2
(-6885 1785);
DISPLAY 0.489362 (-6885 1785);
PAINT MONO (-6885 1785);
FORCEPROP 0 LASTPIN (-6875 1725) $PN CH24
J 2
(-6885 1735);
DISPLAY 0.489362 (-6885 1735);
PAINT MONO (-6885 1735);
FORCEPROP 0 LASTPIN (-6875 1675) $PN CH26
J 2
(-6885 1685);
DISPLAY 0.489362 (-6885 1685);
PAINT MONO (-6885 1685);
FORCEPROP 0 LASTPIN (-6875 1625) $PN CH27
J 2
(-6885 1635);
DISPLAY 0.489362 (-6885 1635);
PAINT MONO (-6885 1635);
FORCEPROP 0 LASTPIN (-6875 1575) $PN CH29
J 2
(-6885 1585);
DISPLAY 0.489362 (-6885 1585);
PAINT MONO (-6885 1585);
FORCEPROP 0 LASTPIN (-6875 1525) $PN CH30
J 2
(-6885 1535);
DISPLAY 0.489362 (-6885 1535);
PAINT MONO (-6885 1535);
FORCEPROP 0 LASTPIN (-6875 1475) $PN CH32
J 2
(-6885 1485);
DISPLAY 0.489362 (-6885 1485);
PAINT MONO (-6885 1485);
FORCEPROP 0 LASTPIN (-6875 1425) $PN CH33
J 2
(-6885 1435);
DISPLAY 0.489362 (-6885 1435);
PAINT MONO (-6885 1435);
FORCEPROP 0 LASTPIN (-6875 1375) $PN CH43
J 2
(-6885 1385);
DISPLAY 0.489362 (-6885 1385);
PAINT MONO (-6885 1385);
FORCEPROP 0 LASTPIN (-6875 1325) $PN CH44
J 2
(-6885 1335);
DISPLAY 0.489362 (-6885 1335);
PAINT MONO (-6885 1335);
FORCEPROP 0 LASTPIN (-6875 1275) $PN CH46
J 2
(-6885 1285);
DISPLAY 0.489362 (-6885 1285);
PAINT MONO (-6885 1285);
FORCEPROP 0 LASTPIN (-6875 1225) $PN CH47
J 2
(-6885 1235);
DISPLAY 0.489362 (-6885 1235);
PAINT MONO (-6885 1235);
FORCEPROP 0 LASTPIN (-6875 1175) $PN CH49
J 2
(-6885 1185);
DISPLAY 0.489362 (-6885 1185);
PAINT MONO (-6885 1185);
FORCEPROP 0 LASTPIN (-6875 1125) $PN CH50
J 2
(-6885 1135);
DISPLAY 0.489362 (-6885 1135);
PAINT MONO (-6885 1135);
FORCEPROP 0 LASTPIN (-6875 1075) $PN CH52
J 2
(-6885 1085);
DISPLAY 0.489362 (-6885 1085);
PAINT MONO (-6885 1085);
FORCEPROP 0 LASTPIN (-6875 1025) $PN CH53
J 2
(-6885 1035);
DISPLAY 0.489362 (-6885 1035);
PAINT MONO (-6885 1035);
FORCEPROP 0 LASTPIN (-6875 975) $PN CK35
J 2
(-6885 985);
DISPLAY 0.489362 (-6885 985);
PAINT MONO (-6885 985);
FORCEPROP 0 LASTPIN (-6875 925) $PN CK36
J 2
(-6885 935);
DISPLAY 0.489362 (-6885 935);
PAINT MONO (-6885 935);
FORCEPROP 0 LASTPIN (-6875 875) $PN CK40
J 2
(-6885 885);
DISPLAY 0.489362 (-6885 885);
PAINT MONO (-6885 885);
FORCEPROP 0 LASTPIN (-6875 825) $PN CK41
J 2
(-6885 835);
DISPLAY 0.489362 (-6885 835);
PAINT MONO (-6885 835);
FORCEPROP 0 LASTPIN (-6875 775) $PN CL29
J 2
(-6885 785);
DISPLAY 0.489362 (-6885 785);
PAINT MONO (-6885 785);
FORCEPROP 0 LASTPIN (-6875 725) $PN CL30
J 2
(-6885 735);
DISPLAY 0.489362 (-6885 735);
PAINT MONO (-6885 735);
FORCEPROP 0 LASTPIN (-5575 6425) $PN CL32
J 0
(-5565 6435);
DISPLAY 0.489362 (-5565 6435);
PAINT MONO (-5565 6435);
FORCEPROP 0 LASTPIN (-5575 6375) $PN CL33
J 0
(-5565 6385);
DISPLAY 0.489362 (-5565 6385);
PAINT MONO (-5565 6385);
FORCEPROP 0 LASTPIN (-5575 6325) $PN CL43
J 0
(-5565 6335);
DISPLAY 0.489362 (-5565 6335);
PAINT MONO (-5565 6335);
FORCEPROP 0 LASTPIN (-5575 6275) $PN CL44
J 0
(-5565 6285);
DISPLAY 0.489362 (-5565 6285);
PAINT MONO (-5565 6285);
FORCEPROP 0 LASTPIN (-5575 6225) $PN CL46
J 0
(-5565 6235);
DISPLAY 0.489362 (-5565 6235);
PAINT MONO (-5565 6235);
FORCEPROP 0 LASTPIN (-5575 6175) $PN CL47
J 0
(-5565 6185);
DISPLAY 0.489362 (-5565 6185);
PAINT MONO (-5565 6185);
FORCEPROP 0 LASTPIN (-5575 6125) $PN CN35
J 0
(-5565 6135);
DISPLAY 0.489362 (-5565 6135);
PAINT MONO (-5565 6135);
FORCEPROP 0 LASTPIN (-5575 6075) $PN CN36
J 0
(-5565 6085);
DISPLAY 0.489362 (-5565 6085);
PAINT MONO (-5565 6085);
FORCEPROP 0 LASTPIN (-5575 6025) $PN CN40
J 0
(-5565 6035);
DISPLAY 0.489362 (-5565 6035);
PAINT MONO (-5565 6035);
FORCEPROP 0 LASTPIN (-5575 5975) $PN CN41
J 0
(-5565 5985);
DISPLAY 0.489362 (-5565 5985);
PAINT MONO (-5565 5985);
FORCEPROP 0 LASTPIN (-5575 5925) $PN CP23
J 0
(-5565 5935);
DISPLAY 0.489362 (-5565 5935);
PAINT MONO (-5565 5935);
FORCEPROP 0 LASTPIN (-5575 5875) $PN CP24
J 0
(-5565 5885);
DISPLAY 0.489362 (-5565 5885);
PAINT MONO (-5565 5885);
FORCEPROP 0 LASTPIN (-5575 5825) $PN CP26
J 0
(-5565 5835);
DISPLAY 0.489362 (-5565 5835);
PAINT MONO (-5565 5835);
FORCEPROP 0 LASTPIN (-5575 5775) $PN CP27
J 0
(-5565 5785);
DISPLAY 0.489362 (-5565 5785);
PAINT MONO (-5565 5785);
FORCEPROP 0 LASTPIN (-5575 5725) $PN CP29
J 0
(-5565 5735);
DISPLAY 0.489362 (-5565 5735);
PAINT MONO (-5565 5735);
FORCEPROP 0 LASTPIN (-5575 5675) $PN CP30
J 0
(-5565 5685);
DISPLAY 0.489362 (-5565 5685);
PAINT MONO (-5565 5685);
FORCEPROP 0 LASTPIN (-5575 5625) $PN CP32
J 0
(-5565 5635);
DISPLAY 0.489362 (-5565 5635);
PAINT MONO (-5565 5635);
FORCEPROP 0 LASTPIN (-5575 5575) $PN CP33
J 0
(-5565 5585);
DISPLAY 0.489362 (-5565 5585);
PAINT MONO (-5565 5585);
FORCEPROP 0 LASTPIN (-5575 5525) $PN CP43
J 0
(-5565 5535);
DISPLAY 0.489362 (-5565 5535);
PAINT MONO (-5565 5535);
FORCEPROP 0 LASTPIN (-5575 5475) $PN CP44
J 0
(-5565 5485);
DISPLAY 0.489362 (-5565 5485);
PAINT MONO (-5565 5485);
FORCEPROP 0 LASTPIN (-5575 5425) $PN CP46
J 0
(-5565 5435);
DISPLAY 0.489362 (-5565 5435);
PAINT MONO (-5565 5435);
FORCEPROP 0 LASTPIN (-5575 5375) $PN CP47
J 0
(-5565 5385);
DISPLAY 0.489362 (-5565 5385);
PAINT MONO (-5565 5385);
FORCEPROP 0 LASTPIN (-5575 5325) $PN CP49
J 0
(-5565 5335);
DISPLAY 0.489362 (-5565 5335);
PAINT MONO (-5565 5335);
FORCEPROP 0 LASTPIN (-5575 5275) $PN CP50
J 0
(-5565 5285);
DISPLAY 0.489362 (-5565 5285);
PAINT MONO (-5565 5285);
FORCEPROP 0 LASTPIN (-5575 5225) $PN CP52
J 0
(-5565 5235);
DISPLAY 0.489362 (-5565 5235);
PAINT MONO (-5565 5235);
FORCEPROP 0 LASTPIN (-5575 5175) $PN CP53
J 0
(-5565 5185);
DISPLAY 0.489362 (-5565 5185);
PAINT MONO (-5565 5185);
FORCEPROP 0 LASTPIN (-5575 5125) $PN CU35
J 0
(-5565 5135);
DISPLAY 0.489362 (-5565 5135);
PAINT MONO (-5565 5135);
FORCEPROP 0 LASTPIN (-5575 5075) $PN CU36
J 0
(-5565 5085);
DISPLAY 0.489362 (-5565 5085);
PAINT MONO (-5565 5085);
FORCEPROP 0 LASTPIN (-5575 5025) $PN CU40
J 0
(-5565 5035);
DISPLAY 0.489362 (-5565 5035);
PAINT MONO (-5565 5035);
FORCEPROP 0 LASTPIN (-5575 4975) $PN CU41
J 0
(-5565 4985);
DISPLAY 0.489362 (-5565 4985);
PAINT MONO (-5565 4985);
FORCEPROP 0 LASTPIN (-5575 4925) $PN CV23
J 0
(-5565 4935);
DISPLAY 0.489362 (-5565 4935);
PAINT MONO (-5565 4935);
FORCEPROP 0 LASTPIN (-5575 4875) $PN CV24
J 0
(-5565 4885);
DISPLAY 0.489362 (-5565 4885);
PAINT MONO (-5565 4885);
FORCEPROP 0 LASTPIN (-5575 4825) $PN CV26
J 0
(-5565 4835);
DISPLAY 0.489362 (-5565 4835);
PAINT MONO (-5565 4835);
FORCEPROP 0 LASTPIN (-5575 4775) $PN CV27
J 0
(-5565 4785);
DISPLAY 0.489362 (-5565 4785);
PAINT MONO (-5565 4785);
FORCEPROP 0 LASTPIN (-5575 4725) $PN CV29
J 0
(-5565 4735);
DISPLAY 0.489362 (-5565 4735);
PAINT MONO (-5565 4735);
FORCEPROP 0 LASTPIN (-5575 4675) $PN CV30
J 0
(-5565 4685);
DISPLAY 0.489362 (-5565 4685);
PAINT MONO (-5565 4685);
FORCEPROP 0 LASTPIN (-5575 4625) $PN CV32
J 0
(-5565 4635);
DISPLAY 0.489362 (-5565 4635);
PAINT MONO (-5565 4635);
FORCEPROP 0 LASTPIN (-5575 4575) $PN CV33
J 0
(-5565 4585);
DISPLAY 0.489362 (-5565 4585);
PAINT MONO (-5565 4585);
FORCEPROP 0 LASTPIN (-5575 4525) $PN CV43
J 0
(-5565 4535);
DISPLAY 0.489362 (-5565 4535);
PAINT MONO (-5565 4535);
FORCEPROP 0 LASTPIN (-5575 4475) $PN CV44
J 0
(-5565 4485);
DISPLAY 0.489362 (-5565 4485);
PAINT MONO (-5565 4485);
FORCEPROP 0 LASTPIN (-5575 4425) $PN CV46
J 0
(-5565 4435);
DISPLAY 0.489362 (-5565 4435);
PAINT MONO (-5565 4435);
FORCEPROP 0 LASTPIN (-5575 4375) $PN CV47
J 0
(-5565 4385);
DISPLAY 0.489362 (-5565 4385);
PAINT MONO (-5565 4385);
FORCEPROP 0 LASTPIN (-5575 4325) $PN CV49
J 0
(-5565 4335);
DISPLAY 0.489362 (-5565 4335);
PAINT MONO (-5565 4335);
FORCEPROP 0 LASTPIN (-5575 4275) $PN CV50
J 0
(-5565 4285);
DISPLAY 0.489362 (-5565 4285);
PAINT MONO (-5565 4285);
FORCEPROP 0 LASTPIN (-5575 4225) $PN CV52
J 0
(-5565 4235);
DISPLAY 0.489362 (-5565 4235);
PAINT MONO (-5565 4235);
FORCEPROP 0 LASTPIN (-5575 4175) $PN CV53
J 0
(-5565 4185);
DISPLAY 0.489362 (-5565 4185);
PAINT MONO (-5565 4185);
FORCEPROP 0 LASTPIN (-5575 4125) $PN DA35
J 0
(-5565 4135);
DISPLAY 0.489362 (-5565 4135);
PAINT MONO (-5565 4135);
FORCEPROP 0 LASTPIN (-5575 4075) $PN DA36
J 0
(-5565 4085);
DISPLAY 0.489362 (-5565 4085);
PAINT MONO (-5565 4085);
FORCEPROP 0 LASTPIN (-5575 4025) $PN DA40
J 0
(-5565 4035);
DISPLAY 0.489362 (-5565 4035);
PAINT MONO (-5565 4035);
FORCEPROP 0 LASTPIN (-5575 3975) $PN DA41
J 0
(-5565 3985);
DISPLAY 0.489362 (-5565 3985);
PAINT MONO (-5565 3985);
FORCEPROP 0 LASTPIN (-5575 3925) $PN DB23
J 0
(-5565 3935);
DISPLAY 0.489362 (-5565 3935);
PAINT MONO (-5565 3935);
FORCEPROP 0 LASTPIN (-5575 3875) $PN DB24
J 0
(-5565 3885);
DISPLAY 0.489362 (-5565 3885);
PAINT MONO (-5565 3885);
FORCEPROP 0 LASTPIN (-5575 3825) $PN DB26
J 0
(-5565 3835);
DISPLAY 0.489362 (-5565 3835);
PAINT MONO (-5565 3835);
FORCEPROP 0 LASTPIN (-5575 3775) $PN DB27
J 0
(-5565 3785);
DISPLAY 0.489362 (-5565 3785);
PAINT MONO (-5565 3785);
FORCEPROP 0 LASTPIN (-5575 3725) $PN DB29
J 0
(-5565 3735);
DISPLAY 0.489362 (-5565 3735);
PAINT MONO (-5565 3735);
FORCEPROP 0 LASTPIN (-5575 3675) $PN DB30
J 0
(-5565 3685);
DISPLAY 0.489362 (-5565 3685);
PAINT MONO (-5565 3685);
FORCEPROP 0 LASTPIN (-5575 3625) $PN DB32
J 0
(-5565 3635);
DISPLAY 0.489362 (-5565 3635);
PAINT MONO (-5565 3635);
FORCEPROP 0 LASTPIN (-5575 3575) $PN DB33
J 0
(-5565 3585);
DISPLAY 0.489362 (-5565 3585);
PAINT MONO (-5565 3585);
FORCEPROP 0 LASTPIN (-5575 3525) $PN DB43
J 0
(-5565 3535);
DISPLAY 0.489362 (-5565 3535);
PAINT MONO (-5565 3535);
FORCEPROP 0 LASTPIN (-5575 3475) $PN DB44
J 0
(-5565 3485);
DISPLAY 0.489362 (-5565 3485);
PAINT MONO (-5565 3485);
FORCEPROP 0 LASTPIN (-5575 3425) $PN DB46
J 0
(-5565 3435);
DISPLAY 0.489362 (-5565 3435);
PAINT MONO (-5565 3435);
FORCEPROP 0 LASTPIN (-5575 3375) $PN DB47
J 0
(-5565 3385);
DISPLAY 0.489362 (-5565 3385);
PAINT MONO (-5565 3385);
FORCEPROP 0 LASTPIN (-5575 3325) $PN DB49
J 0
(-5565 3335);
DISPLAY 0.489362 (-5565 3335);
PAINT MONO (-5565 3335);
FORCEPROP 0 LASTPIN (-5575 3275) $PN DB50
J 0
(-5565 3285);
DISPLAY 0.489362 (-5565 3285);
PAINT MONO (-5565 3285);
FORCEPROP 0 LASTPIN (-5575 3225) $PN DB52
J 0
(-5565 3235);
DISPLAY 0.489362 (-5565 3235);
PAINT MONO (-5565 3235);
FORCEPROP 0 LASTPIN (-5575 3175) $PN DB53
J 0
(-5565 3185);
DISPLAY 0.489362 (-5565 3185);
PAINT MONO (-5565 3185);
FORCEPROP 0 LASTPIN (-5575 3125) $PN DC35
J 0
(-5565 3135);
DISPLAY 0.489362 (-5565 3135);
PAINT MONO (-5565 3135);
FORCEPROP 0 LASTPIN (-5575 3075) $PN DC36
J 0
(-5565 3085);
DISPLAY 0.489362 (-5565 3085);
PAINT MONO (-5565 3085);
FORCEPROP 0 LASTPIN (-5575 3025) $PN DC40
J 0
(-5565 3035);
DISPLAY 0.489362 (-5565 3035);
PAINT MONO (-5565 3035);
FORCEPROP 0 LASTPIN (-5575 2975) $PN DC41
J 0
(-5565 2985);
DISPLAY 0.489362 (-5565 2985);
PAINT MONO (-5565 2985);
FORCEPROP 0 LASTPIN (-5575 2925) $PN DD22
J 0
(-5565 2935);
DISPLAY 0.489362 (-5565 2935);
PAINT MONO (-5565 2935);
FORCEPROP 0 LASTPIN (-5575 2875) $PN DD25
J 0
(-5565 2885);
DISPLAY 0.489362 (-5565 2885);
PAINT MONO (-5565 2885);
FORCEPROP 0 LASTPIN (-5575 2825) $PN DD28
J 0
(-5565 2835);
DISPLAY 0.489362 (-5565 2835);
PAINT MONO (-5565 2835);
FORCEPROP 0 LASTPIN (-5575 2775) $PN DD31
J 0
(-5565 2785);
DISPLAY 0.489362 (-5565 2785);
PAINT MONO (-5565 2785);
FORCEPROP 0 LASTPIN (-5575 2725) $PN DD34
J 0
(-5565 2735);
DISPLAY 0.489362 (-5565 2735);
PAINT MONO (-5565 2735);
FORCEPROP 0 LASTPIN (-5575 2675) $PN DD42
J 0
(-5565 2685);
DISPLAY 0.489362 (-5565 2685);
PAINT MONO (-5565 2685);
FORCEPROP 0 LASTPIN (-5575 2625) $PN DD45
J 0
(-5565 2635);
DISPLAY 0.489362 (-5565 2635);
PAINT MONO (-5565 2635);
FORCEPROP 0 LASTPIN (-5575 2575) $PN DD48
J 0
(-5565 2585);
DISPLAY 0.489362 (-5565 2585);
PAINT MONO (-5565 2585);
FORCEPROP 0 LASTPIN (-5575 2525) $PN DD51
J 0
(-5565 2535);
DISPLAY 0.489362 (-5565 2535);
PAINT MONO (-5565 2535);
FORCEPROP 0 LASTPIN (-5575 2475) $PN DD54
J 0
(-5565 2485);
DISPLAY 0.489362 (-5565 2485);
PAINT MONO (-5565 2485);
FORCEPROP 0 LASTPIN (-5575 2425) $PN DE22
J 0
(-5565 2435);
DISPLAY 0.489362 (-5565 2435);
PAINT MONO (-5565 2435);
FORCEPROP 0 LASTPIN (-5575 2375) $PN DE25
J 0
(-5565 2385);
DISPLAY 0.489362 (-5565 2385);
PAINT MONO (-5565 2385);
FORCEPROP 0 LASTPIN (-5575 2325) $PN DE28
J 0
(-5565 2335);
DISPLAY 0.489362 (-5565 2335);
PAINT MONO (-5565 2335);
FORCEPROP 0 LASTPIN (-5575 2275) $PN DE31
J 0
(-5565 2285);
DISPLAY 0.489362 (-5565 2285);
PAINT MONO (-5565 2285);
FORCEPROP 0 LASTPIN (-5575 2225) $PN DE34
J 0
(-5565 2235);
DISPLAY 0.489362 (-5565 2235);
PAINT MONO (-5565 2235);
FORCEPROP 0 LASTPIN (-5575 2175) $PN DE35
J 0
(-5565 2185);
DISPLAY 0.489362 (-5565 2185);
PAINT MONO (-5565 2185);
FORCEPROP 0 LASTPIN (-5575 2125) $PN DE41
J 0
(-5565 2135);
DISPLAY 0.489362 (-5565 2135);
PAINT MONO (-5565 2135);
FORCEPROP 0 LASTPIN (-5575 2075) $PN DE42
J 0
(-5565 2085);
DISPLAY 0.489362 (-5565 2085);
PAINT MONO (-5565 2085);
FORCEPROP 0 LASTPIN (-5575 2025) $PN DE45
J 0
(-5565 2035);
DISPLAY 0.489362 (-5565 2035);
PAINT MONO (-5565 2035);
FORCEPROP 0 LASTPIN (-5575 1975) $PN DE48
J 0
(-5565 1985);
DISPLAY 0.489362 (-5565 1985);
PAINT MONO (-5565 1985);
FORCEPROP 0 LASTPIN (-5575 1925) $PN DE51
J 0
(-5565 1935);
DISPLAY 0.489362 (-5565 1935);
PAINT MONO (-5565 1935);
FORCEPROP 0 LASTPIN (-5575 1875) $PN DE54
J 0
(-5565 1885);
DISPLAY 0.489362 (-5565 1885);
PAINT MONO (-5565 1885);
FORCEPROP 0 LASTPIN (-5575 1825) $PN DG19
J 0
(-5565 1835);
DISPLAY 0.489362 (-5565 1835);
PAINT MONO (-5565 1835);
FORCEPROP 0 LASTPIN (-5575 1775) $PN DG57
J 0
(-5565 1785);
DISPLAY 0.489362 (-5565 1785);
PAINT MONO (-5565 1785);
FORCEPROP 0 LASTPIN (-5575 1725) $PN DH19
J 0
(-5565 1735);
DISPLAY 0.489362 (-5565 1735);
PAINT MONO (-5565 1735);
FORCEPROP 0 LASTPIN (-5575 1675) $PN DH20
J 0
(-5565 1685);
DISPLAY 0.489362 (-5565 1685);
PAINT MONO (-5565 1685);
FORCEPROP 0 LASTPIN (-5575 1625) $PN DH22
J 0
(-5565 1635);
DISPLAY 0.489362 (-5565 1635);
PAINT MONO (-5565 1635);
FORCEPROP 0 LASTPIN (-5575 1575) $PN DH23
J 0
(-5565 1585);
DISPLAY 0.489362 (-5565 1585);
PAINT MONO (-5565 1585);
FORCEPROP 0 LASTPIN (-5575 1525) $PN DH25
J 0
(-5565 1535);
DISPLAY 0.489362 (-5565 1535);
PAINT MONO (-5565 1535);
FORCEPROP 0 LASTPIN (-5575 1475) $PN DH26
J 0
(-5565 1485);
DISPLAY 0.489362 (-5565 1485);
PAINT MONO (-5565 1485);
FORCEPROP 0 LASTPIN (-5575 1425) $PN DH28
J 0
(-5565 1435);
DISPLAY 0.489362 (-5565 1435);
PAINT MONO (-5565 1435);
FORCEPROP 0 LASTPIN (-5575 1375) $PN DH29
J 0
(-5565 1385);
DISPLAY 0.489362 (-5565 1385);
PAINT MONO (-5565 1385);
FORCEPROP 0 LASTPIN (-5575 1325) $PN DH31
J 0
(-5565 1335);
DISPLAY 0.489362 (-5565 1335);
PAINT MONO (-5565 1335);
FORCEPROP 0 LASTPIN (-5575 1275) $PN DH32
J 0
(-5565 1285);
DISPLAY 0.489362 (-5565 1285);
PAINT MONO (-5565 1285);
FORCEPROP 0 LASTPIN (-5575 1225) $PN DH34
J 0
(-5565 1235);
DISPLAY 0.489362 (-5565 1235);
PAINT MONO (-5565 1235);
FORCEPROP 0 LASTPIN (-5575 1175) $PN DH35
J 0
(-5565 1185);
DISPLAY 0.489362 (-5565 1185);
PAINT MONO (-5565 1185);
FORCEPROP 0 LASTPIN (-5575 1125) $PN DH41
J 0
(-5565 1135);
DISPLAY 0.489362 (-5565 1135);
PAINT MONO (-5565 1135);
FORCEPROP 0 LASTPIN (-5575 1075) $PN DH42
J 0
(-5565 1085);
DISPLAY 0.489362 (-5565 1085);
PAINT MONO (-5565 1085);
FORCEPROP 0 LASTPIN (-5575 1025) $PN DH44
J 0
(-5565 1035);
DISPLAY 0.489362 (-5565 1035);
PAINT MONO (-5565 1035);
FORCEPROP 0 LASTPIN (-5575 975) $PN DH45
J 0
(-5565 985);
DISPLAY 0.489362 (-5565 985);
PAINT MONO (-5565 985);
FORCEPROP 0 LASTPIN (-5575 925) $PN DH47
J 0
(-5565 935);
DISPLAY 0.489362 (-5565 935);
PAINT MONO (-5565 935);
FORCEPROP 0 LASTPIN (-5575 875) $PN DH48
J 0
(-5565 885);
DISPLAY 0.489362 (-5565 885);
PAINT MONO (-5565 885);
FORCEPROP 0 LASTPIN (-5575 825) $PN DH50
J 0
(-5565 835);
DISPLAY 0.489362 (-5565 835);
PAINT MONO (-5565 835);
FORCEPROP 0 LASTPIN (-5575 775) $PN DH51
J 0
(-5565 785);
DISPLAY 0.489362 (-5565 785);
PAINT MONO (-5565 785);
FORCEPROP 0 LASTPIN (-5575 725) $PN DH53
J 0
(-5565 735);
DISPLAY 0.489362 (-5565 735);
PAINT MONO (-5565 735);
FORCEPROP 0 LASTPIN (-5575 675) $PN DH54
J 0
(-5565 685);
DISPLAY 0.489362 (-5565 685);
PAINT MONO (-5565 685);
FORCEPROP 0 LASTPIN (-5575 625) $PN DH56
J 0
(-5565 635);
DISPLAY 0.489362 (-5565 635);
PAINT MONO (-5565 635);
FORCEPROP 0 LASTPIN (-5575 575) $PN DH57
J 0
(-5565 585);
DISPLAY 0.489362 (-5565 585);
PAINT MONO (-5565 585);
FORCEPROP 2 LAST VALUE SOCKET6096_13568-001
J 0
(-6625 6600);
DISPLAY 0.489362 (-6625 6600);
PAINT SKYBLUE (-6625 6600);
FORCEPROP 1 LAST MATERIAL IO
J 0
(-6720 6607);
DISPLAY 0.489362 (-6720 6607);
PAINT SKYBLUE (-6720 6607);
FORCEPROP 2 LAST PART_TYPE SMLF
J 0
(-6650 6675);
DISPLAY 1.021277 (-6650 6675);
FORCEPROP 1 LAST NEEDS_NO_SIZE TRUE
J 0
(-6225 3375);
DISPLAY 0.723404 (-6225 3375);
PAINT GREEN (-6225 3375);
DISPLAY INVISIBLE (-6225 3375);
FORCEPROP 1 LAST CDS_LMAN_SYM_OUTLINE -500,3200,500,-3200
J 0
(-6225 3375);
DISPLAY 0.468085 (-6225 3375);
PAINT GREEN (-6225 3375);
DISPLAY INVISIBLE (-6225 3375);
FORCEPROP 2 LAST CDS_LIB pure_quanta
J 0
(-6225 3375);
DISPLAY INVISIBLE (-6225 3375);
FORCEPROP 1 LAST PATH I32
J 0
(-6225 3375);
DISPLAY 0.723404 (-6225 3375);
PAINT GREEN (-6225 3375);
DISPLAY INVISIBLE (-6225 3375);
FORCEPROP 1 LAST PART_NUMBER DGA^6000030
J 0
(-6725 6650);
DISPLAY 0.489362 (-6725 6650);
PAINT SKYBLUE (-6725 6650);
DISPLAY INVISIBLE (-6725 6650);
FORCEADD VCC_CORE..1
(-2050 6575);
FORCEPROP 3 LASTPIN (-2050 6525) SIG_NAME PVDDIO_P1\g
J 0
(-2040 6535);
DISPLAY 0.659574 (-2040 6535);
PAINT MONO (-2040 6535);
DISPLAY INVISIBLE (-2040 6535);
FORCEPROP 1 LAST HDL_POWER PVDDIO_P1
J 1
(-2050 6625);
DISPLAY 0.489362 (-2050 6625);
PAINT GREEN (-2050 6625);
FORCEPROP 2 LAST CDS_LIB pure_quanta_power
J 0
(-2050 6575);
DISPLAY INVISIBLE (-2050 6575);
FORCEPROP 1 LAST PATH I36
J 0
(-2000 6600);
DISPLAY 0.872340 (-2000 6600);
PAINT AQUA (-2000 6600);
DISPLAY INVISIBLE (-2000 6600);
FORCEADD UNIVERSAL_POWER..1
(-1125 950);
FORCEPROP 3 LASTPIN (-1125 900) SIG_NAME PVDD18_S5_P1\g
J 0
(-1115 910);
DISPLAY 0.659574 (-1115 910);
PAINT MONO (-1115 910);
DISPLAY INVISIBLE (-1115 910);
FORCEPROP 1 LAST HDL_POWER PVDD18_S5_P1
J 1
(-1125 1000);
DISPLAY 0.489362 (-1125 1000);
PAINT GREEN (-1125 1000);
FORCEPROP 2 LAST CDS_LIB pure_quanta_power
J 0
(-1125 950);
DISPLAY INVISIBLE (-1125 950);
FORCEPROP 1 LAST PATH I37
J 0
(-1075 975);
DISPLAY 0.872340 (-1075 975);
PAINT AQUA (-1075 975);
DISPLAY INVISIBLE (-1075 975);
FORCEADD UNIVERSAL_POWER..1
(-1450 950);
FORCEPROP 3 LASTPIN (-1450 900) SIG_NAME P1V5_BAT\g
J 0
(-1440 910);
DISPLAY 0.659574 (-1440 910);
PAINT MONO (-1440 910);
DISPLAY INVISIBLE (-1440 910);
FORCEPROP 1 LAST HDL_POWER P1V5_BAT
J 1
(-1450 1000);
DISPLAY 0.489362 (-1450 1000);
PAINT GREEN (-1450 1000);
FORCEPROP 2 LAST CDS_LIB pure_quanta_power
J 0
(-1450 950);
DISPLAY INVISIBLE (-1450 950);
FORCEPROP 1 LAST PATH I38
J 0
(-1400 975);
DISPLAY 0.872340 (-1400 975);
PAINT AQUA (-1400 975);
DISPLAY INVISIBLE (-1400 975);
FORCEADD VCC_CORE..1
(-3550 6575);
FORCEPROP 3 LASTPIN (-3550 6525) SIG_NAME PVDD11_S3_P1\g
J 0
(-3540 6535);
DISPLAY 0.659574 (-3540 6535);
PAINT MONO (-3540 6535);
DISPLAY INVISIBLE (-3540 6535);
FORCEPROP 1 LAST HDL_POWER PVDD11_S3_P1
J 1
(-3550 6625);
DISPLAY 0.489362 (-3550 6625);
PAINT GREEN (-3550 6625);
FORCEPROP 2 LAST CDS_LIB pure_quanta_power
J 0
(-3550 6575);
DISPLAY INVISIBLE (-3550 6575);
FORCEPROP 1 LAST PATH I41
J 0
(-3500 6600);
DISPLAY 0.872340 (-3500 6600);
PAINT AQUA (-3500 6600);
DISPLAY INVISIBLE (-3500 6600);
FORCEADD UNIVERSAL_POWER..1
(-3725 2700);
FORCEPROP 3 LASTPIN (-3725 2650) SIG_NAME PVDD18_S5_P1\g
J 0
(-3715 2660);
DISPLAY 0.659574 (-3715 2660);
PAINT MONO (-3715 2660);
DISPLAY INVISIBLE (-3715 2660);
FORCEPROP 1 LAST HDL_POWER PVDD18_S5_P1
J 1
(-3725 2750);
DISPLAY 0.489362 (-3725 2750);
PAINT GREEN (-3725 2750);
FORCEPROP 2 LAST CDS_LIB pure_quanta_power
J 0
(-3725 2700);
DISPLAY INVISIBLE (-3725 2700);
FORCEPROP 1 LAST PATH I42
J 0
(-3675 2725);
DISPLAY 0.872340 (-3675 2725);
PAINT AQUA (-3675 2725);
DISPLAY INVISIBLE (-3675 2725);
FORCEADD UNIVERSAL_POWER..1
(-3725 1050);
FORCEPROP 3 LASTPIN (-3725 1000) SIG_NAME PVDD_33_S5\g
J 0
(-3715 1010);
DISPLAY 0.659574 (-3715 1010);
PAINT MONO (-3715 1010);
DISPLAY INVISIBLE (-3715 1010);
FORCEPROP 1 LAST HDL_POWER PVDD_33_S5
J 1
(-3725 1100);
DISPLAY 0.489362 (-3725 1100);
PAINT GREEN (-3725 1100);
FORCEPROP 2 LAST CDS_LIB pure_quanta_power
J 0
(-3725 1050);
DISPLAY INVISIBLE (-3725 1050);
FORCEPROP 1 LAST PATH I44
J 0
(-3675 1075);
DISPLAY 0.872340 (-3675 1075);
PAINT AQUA (-3675 1075);
DISPLAY INVISIBLE (-3675 1075);
FORCEADD GENOA_SP5..27
(-2800 3500);
FORCEPROP 1 LAST LOCATION U26
J 0
(-3300 6700);
DISPLAY 0.489362 (-3300 6700);
PAINT SKYBLUE (-3300 6700);
FORCEPROP 0 LAST $SEC 27
J 0
(-3275 6925);
DISPLAY 0.680851 (-3275 6925);
PAINT MONO (-3275 6925);
DISPLAY INVISIBLE (-3275 6925);
FORCEPROP 0 LAST CDS_SEC 27
J 0
(-3275 6925);
DISPLAY 1.021277 (-3275 6925);
DISPLAY INVISIBLE (-3275 6925);
FORCEPROP 0 LASTPIN (-3450 6475) $PN BJ18
J 2
(-3460 6485);
DISPLAY 0.489362 (-3460 6485);
PAINT MONO (-3460 6485);
FORCEPROP 0 LASTPIN (-3450 6425) $PN BJ23
J 2
(-3460 6435);
DISPLAY 0.489362 (-3460 6435);
PAINT MONO (-3460 6435);
FORCEPROP 0 LASTPIN (-3450 6375) $PN BJ25
J 2
(-3460 6385);
DISPLAY 0.489362 (-3460 6385);
PAINT MONO (-3460 6385);
FORCEPROP 0 LASTPIN (-3450 6325) $PN BJ27
J 2
(-3460 6335);
DISPLAY 0.489362 (-3460 6335);
PAINT MONO (-3460 6335);
FORCEPROP 0 LASTPIN (-3450 6275) $PN BK22
J 2
(-3460 6285);
DISPLAY 0.489362 (-3460 6285);
PAINT MONO (-3460 6285);
FORCEPROP 0 LASTPIN (-3450 6225) $PN BK24
J 2
(-3460 6235);
DISPLAY 0.489362 (-3460 6235);
PAINT MONO (-3460 6235);
FORCEPROP 0 LASTPIN (-3450 6175) $PN BK26
J 2
(-3460 6185);
DISPLAY 0.489362 (-3460 6185);
PAINT MONO (-3460 6185);
FORCEPROP 0 LASTPIN (-3450 6125) $PN BK28
J 2
(-3460 6135);
DISPLAY 0.489362 (-3460 6135);
PAINT MONO (-3460 6135);
FORCEPROP 0 LASTPIN (-3450 6075) $PN BK49
J 2
(-3460 6085);
DISPLAY 0.489362 (-3460 6085);
PAINT MONO (-3460 6085);
FORCEPROP 0 LASTPIN (-3450 6025) $PN BL23
J 2
(-3460 6035);
DISPLAY 0.489362 (-3460 6035);
PAINT MONO (-3460 6035);
FORCEPROP 0 LASTPIN (-3450 5975) $PN BL25
J 2
(-3460 5985);
DISPLAY 0.489362 (-3460 5985);
PAINT MONO (-3460 5985);
FORCEPROP 0 LASTPIN (-3450 5925) $PN BL27
J 2
(-3460 5935);
DISPLAY 0.489362 (-3460 5935);
PAINT MONO (-3460 5935);
FORCEPROP 0 LASTPIN (-3450 5875) $PN BL48
J 2
(-3460 5885);
DISPLAY 0.489362 (-3460 5885);
PAINT MONO (-3460 5885);
FORCEPROP 0 LASTPIN (-3450 5825) $PN BM12
J 2
(-3460 5835);
DISPLAY 0.489362 (-3460 5835);
PAINT MONO (-3460 5835);
FORCEPROP 0 LASTPIN (-3450 5775) $PN BM19
J 2
(-3460 5785);
DISPLAY 0.489362 (-3460 5785);
PAINT MONO (-3460 5785);
FORCEPROP 0 LASTPIN (-3450 5725) $PN BM22
J 2
(-3460 5735);
DISPLAY 0.489362 (-3460 5735);
PAINT MONO (-3460 5735);
FORCEPROP 0 LASTPIN (-3450 5675) $PN BM24
J 2
(-3460 5685);
DISPLAY 0.489362 (-3460 5685);
PAINT MONO (-3460 5685);
FORCEPROP 0 LASTPIN (-3450 5625) $PN BM26
J 2
(-3460 5635);
DISPLAY 0.489362 (-3460 5635);
PAINT MONO (-3460 5635);
FORCEPROP 0 LASTPIN (-3450 5575) $PN BM28
J 2
(-3460 5585);
DISPLAY 0.489362 (-3460 5585);
PAINT MONO (-3460 5585);
FORCEPROP 0 LASTPIN (-3450 5525) $PN BM30
J 2
(-3460 5535);
DISPLAY 0.489362 (-3460 5535);
PAINT MONO (-3460 5535);
FORCEPROP 0 LASTPIN (-3450 5475) $PN BM32
J 2
(-3460 5485);
DISPLAY 0.489362 (-3460 5485);
PAINT MONO (-3460 5485);
FORCEPROP 0 LASTPIN (-3450 5425) $PN BM34
J 2
(-3460 5435);
DISPLAY 0.489362 (-3460 5435);
PAINT MONO (-3460 5435);
FORCEPROP 0 LASTPIN (-3450 5375) $PN BM36
J 2
(-3460 5385);
DISPLAY 0.489362 (-3460 5385);
PAINT MONO (-3460 5385);
FORCEPROP 0 LASTPIN (-3450 5325) $PN BM39
J 2
(-3460 5335);
DISPLAY 0.489362 (-3460 5335);
PAINT MONO (-3460 5335);
FORCEPROP 0 LASTPIN (-3450 5275) $PN BM41
J 2
(-3460 5285);
DISPLAY 0.489362 (-3460 5285);
PAINT MONO (-3460 5285);
FORCEPROP 0 LASTPIN (-3450 5225) $PN BM43
J 2
(-3460 5235);
DISPLAY 0.489362 (-3460 5235);
PAINT MONO (-3460 5235);
FORCEPROP 0 LASTPIN (-3450 5175) $PN BM45
J 2
(-3460 5185);
DISPLAY 0.489362 (-3460 5185);
PAINT MONO (-3460 5185);
FORCEPROP 0 LASTPIN (-3450 5125) $PN BM47
J 2
(-3460 5135);
DISPLAY 0.489362 (-3460 5135);
PAINT MONO (-3460 5135);
FORCEPROP 0 LASTPIN (-3450 5075) $PN BM49
J 2
(-3460 5085);
DISPLAY 0.489362 (-3460 5085);
PAINT MONO (-3460 5085);
FORCEPROP 0 LASTPIN (-3450 5025) $PN BN25
J 2
(-3460 5035);
DISPLAY 0.489362 (-3460 5035);
PAINT MONO (-3460 5035);
FORCEPROP 0 LASTPIN (-3450 4975) $PN BN29
J 2
(-3460 4985);
DISPLAY 0.489362 (-3460 4985);
PAINT MONO (-3460 4985);
FORCEPROP 0 LASTPIN (-3450 4925) $PN BN33
J 2
(-3460 4935);
DISPLAY 0.489362 (-3460 4935);
PAINT MONO (-3460 4935);
FORCEPROP 0 LASTPIN (-3450 4875) $PN BN40
J 2
(-3460 4885);
DISPLAY 0.489362 (-3460 4885);
PAINT MONO (-3460 4885);
FORCEPROP 0 LASTPIN (-3450 4825) $PN BN44
J 2
(-3460 4835);
DISPLAY 0.489362 (-3460 4835);
PAINT MONO (-3460 4835);
FORCEPROP 0 LASTPIN (-3450 4775) $PN BN48
J 2
(-3460 4785);
DISPLAY 0.489362 (-3460 4785);
PAINT MONO (-3460 4785);
FORCEPROP 0 LASTPIN (-3450 4725) $PN BP22
J 2
(-3460 4735);
DISPLAY 0.489362 (-3460 4735);
PAINT MONO (-3460 4735);
FORCEPROP 0 LASTPIN (-3450 4675) $PN BR4
J 2
(-3460 4685);
DISPLAY 0.489362 (-3460 4685);
PAINT MONO (-3460 4685);
FORCEPROP 0 LASTPIN (-3450 4625) $PN BR11
J 2
(-3460 4635);
DISPLAY 0.489362 (-3460 4635);
PAINT MONO (-3460 4635);
FORCEPROP 0 LASTPIN (-3450 4575) $PN BR18
J 2
(-3460 4585);
DISPLAY 0.489362 (-3460 4585);
PAINT MONO (-3460 4585);
FORCEPROP 0 LASTPIN (-3450 4525) $PN BV5
J 2
(-3460 4535);
DISPLAY 0.489362 (-3460 4535);
PAINT MONO (-3460 4535);
FORCEPROP 0 LASTPIN (-3450 4475) $PN BV12
J 2
(-3460 4485);
DISPLAY 0.489362 (-3460 4485);
PAINT MONO (-3460 4485);
FORCEPROP 0 LASTPIN (-3450 4425) $PN BV19
J 2
(-3460 4435);
DISPLAY 0.489362 (-3460 4435);
PAINT MONO (-3460 4435);
FORCEPROP 0 LASTPIN (-3450 4375) $PN BV22
J 2
(-3460 4385);
DISPLAY 0.489362 (-3460 4385);
PAINT MONO (-3460 4385);
FORCEPROP 0 LASTPIN (-3450 4325) $PN CA4
J 2
(-3460 4335);
DISPLAY 0.489362 (-3460 4335);
PAINT MONO (-3460 4335);
FORCEPROP 0 LASTPIN (-3450 4275) $PN CA11
J 2
(-3460 4285);
DISPLAY 0.489362 (-3460 4285);
PAINT MONO (-3460 4285);
FORCEPROP 0 LASTPIN (-3450 4225) $PN CA18
J 2
(-3460 4235);
DISPLAY 0.489362 (-3460 4235);
PAINT MONO (-3460 4235);
FORCEPROP 0 LASTPIN (-3450 4175) $PN CB22
J 2
(-3460 4185);
DISPLAY 0.489362 (-3460 4185);
PAINT MONO (-3460 4185);
FORCEPROP 0 LASTPIN (-3450 4125) $PN CD5
J 2
(-3460 4135);
DISPLAY 0.489362 (-3460 4135);
PAINT MONO (-3460 4135);
FORCEPROP 0 LASTPIN (-3450 4075) $PN CD12
J 2
(-3460 4085);
DISPLAY 0.489362 (-3460 4085);
PAINT MONO (-3460 4085);
FORCEPROP 0 LASTPIN (-3450 4025) $PN CD19
J 2
(-3460 4035);
DISPLAY 0.489362 (-3460 4035);
PAINT MONO (-3460 4035);
FORCEPROP 0 LASTPIN (-3450 3975) $PN CF22
J 2
(-3460 3985);
DISPLAY 0.489362 (-3460 3985);
PAINT MONO (-3460 3985);
FORCEPROP 0 LASTPIN (-3450 3925) $PN CG4
J 2
(-3460 3935);
DISPLAY 0.489362 (-3460 3935);
PAINT MONO (-3460 3935);
FORCEPROP 0 LASTPIN (-3450 3875) $PN CG11
J 2
(-3460 3885);
DISPLAY 0.489362 (-3460 3885);
PAINT MONO (-3460 3885);
FORCEPROP 0 LASTPIN (-3450 3825) $PN CG18
J 2
(-3460 3835);
DISPLAY 0.489362 (-3460 3835);
PAINT MONO (-3460 3835);
FORCEPROP 0 LASTPIN (-3450 3775) $PN CJ22
J 2
(-3460 3785);
DISPLAY 0.489362 (-3460 3785);
PAINT MONO (-3460 3785);
FORCEPROP 0 LASTPIN (-3450 3725) $PN CK5
J 2
(-3460 3735);
DISPLAY 0.489362 (-3460 3735);
PAINT MONO (-3460 3735);
FORCEPROP 0 LASTPIN (-3450 3675) $PN CK12
J 2
(-3460 3685);
DISPLAY 0.489362 (-3460 3685);
PAINT MONO (-3460 3685);
FORCEPROP 0 LASTPIN (-3450 3625) $PN CK19
J 2
(-3460 3635);
DISPLAY 0.489362 (-3460 3635);
PAINT MONO (-3460 3635);
FORCEPROP 0 LASTPIN (-3450 3575) $PN CM22
J 2
(-3460 3585);
DISPLAY 0.489362 (-3460 3585);
PAINT MONO (-3460 3585);
FORCEPROP 0 LASTPIN (-3450 3525) $PN CN4
J 2
(-3460 3535);
DISPLAY 0.489362 (-3460 3535);
PAINT MONO (-3460 3535);
FORCEPROP 0 LASTPIN (-3450 3475) $PN CN11
J 2
(-3460 3485);
DISPLAY 0.489362 (-3460 3485);
PAINT MONO (-3460 3485);
FORCEPROP 0 LASTPIN (-3450 3425) $PN CN18
J 2
(-3460 3435);
DISPLAY 0.489362 (-3460 3435);
PAINT MONO (-3460 3435);
FORCEPROP 0 LASTPIN (-3450 3375) $PN CT5
J 2
(-3460 3385);
DISPLAY 0.489362 (-3460 3385);
PAINT MONO (-3460 3385);
FORCEPROP 0 LASTPIN (-3450 3325) $PN CT12
J 2
(-3460 3335);
DISPLAY 0.489362 (-3460 3335);
PAINT MONO (-3460 3335);
FORCEPROP 0 LASTPIN (-3450 3275) $PN CT19
J 2
(-3460 3285);
DISPLAY 0.489362 (-3460 3285);
PAINT MONO (-3460 3285);
FORCEPROP 0 LASTPIN (-3450 3225) $PN CT22
J 2
(-3460 3235);
DISPLAY 0.489362 (-3460 3235);
PAINT MONO (-3460 3235);
FORCEPROP 0 LASTPIN (-3450 3175) $PN CW4
J 2
(-3460 3185);
DISPLAY 0.489362 (-3460 3185);
PAINT MONO (-3460 3185);
FORCEPROP 0 LASTPIN (-3450 3125) $PN CW11
J 2
(-3460 3135);
DISPLAY 0.489362 (-3460 3135);
PAINT MONO (-3460 3135);
FORCEPROP 0 LASTPIN (-3450 3075) $PN CW18
J 2
(-3460 3085);
DISPLAY 0.489362 (-3460 3085);
PAINT MONO (-3460 3085);
FORCEPROP 0 LASTPIN (-3450 3025) $PN CY22
J 2
(-3460 3035);
DISPLAY 0.489362 (-3460 3035);
PAINT MONO (-3460 3035);
FORCEPROP 0 LASTPIN (-3450 2975) $PN DB5
J 2
(-3460 2985);
DISPLAY 0.489362 (-3460 2985);
PAINT MONO (-3460 2985);
FORCEPROP 0 LASTPIN (-3450 2925) $PN DB12
J 2
(-3460 2935);
DISPLAY 0.489362 (-3460 2935);
PAINT MONO (-3460 2935);
FORCEPROP 0 LASTPIN (-3450 2875) $PN DB19
J 2
(-3460 2885);
DISPLAY 0.489362 (-3460 2885);
PAINT MONO (-3460 2885);
FORCEPROP 0 LASTPIN (-3450 2825) $PN DE4
J 2
(-3460 2835);
DISPLAY 0.489362 (-3460 2835);
PAINT MONO (-3460 2835);
FORCEPROP 0 LASTPIN (-3450 2775) $PN DE11
J 2
(-3460 2785);
DISPLAY 0.489362 (-3460 2785);
PAINT MONO (-3460 2785);
FORCEPROP 0 LASTPIN (-3450 2725) $PN DE18
J 2
(-3460 2735);
DISPLAY 0.489362 (-3460 2735);
PAINT MONO (-3460 2735);
FORCEPROP 0 LASTPIN (-3450 2675) $PN DG5
J 2
(-3460 2685);
DISPLAY 0.489362 (-3460 2685);
PAINT MONO (-3460 2685);
FORCEPROP 0 LASTPIN (-3450 2475) $PN AR52
J 2
(-3460 2485);
DISPLAY 0.489362 (-3460 2485);
PAINT MONO (-3460 2485);
FORCEPROP 0 LASTPIN (-3450 2425) $PN AR54
J 2
(-3460 2435);
DISPLAY 0.489362 (-3460 2435);
PAINT MONO (-3460 2435);
FORCEPROP 0 LASTPIN (-3450 2375) $PN AT51
J 2
(-3460 2385);
DISPLAY 0.489362 (-3460 2385);
PAINT MONO (-3460 2385);
FORCEPROP 0 LASTPIN (-3450 2325) $PN AT53
J 2
(-3460 2335);
DISPLAY 0.489362 (-3460 2335);
PAINT MONO (-3460 2335);
FORCEPROP 0 LASTPIN (-3450 2275) $PN AU50
J 2
(-3460 2285);
DISPLAY 0.489362 (-3460 2285);
PAINT MONO (-3460 2285);
FORCEPROP 0 LASTPIN (-3450 2225) $PN AU52
J 2
(-3460 2235);
DISPLAY 0.489362 (-3460 2235);
PAINT MONO (-3460 2235);
FORCEPROP 0 LASTPIN (-3450 1125) $PN AU54
J 2
(-3460 1135);
DISPLAY 0.489362 (-3460 1135);
PAINT MONO (-3460 1135);
FORCEPROP 0 LASTPIN (-3450 2175) $PN AV49
J 2
(-3460 2185);
DISPLAY 0.489362 (-3460 2185);
PAINT MONO (-3460 2185);
FORCEPROP 0 LASTPIN (-3450 2125) $PN AV51
J 2
(-3460 2135);
DISPLAY 0.489362 (-3460 2135);
PAINT MONO (-3460 2135);
FORCEPROP 0 LASTPIN (-3450 2075) $PN AV53
J 2
(-3460 2085);
DISPLAY 0.489362 (-3460 2085);
PAINT MONO (-3460 2085);
FORCEPROP 0 LASTPIN (-3450 2025) $PN AW50
J 2
(-3460 2035);
DISPLAY 0.489362 (-3460 2035);
PAINT MONO (-3460 2035);
FORCEPROP 0 LASTPIN (-3450 1975) $PN AW52
J 2
(-3460 1985);
DISPLAY 0.489362 (-3460 1985);
PAINT MONO (-3460 1985);
FORCEPROP 0 LASTPIN (-3450 1925) $PN AW54
J 2
(-3460 1935);
DISPLAY 0.489362 (-3460 1935);
PAINT MONO (-3460 1935);
FORCEPROP 0 LASTPIN (-3450 1875) $PN AY51
J 2
(-3460 1885);
DISPLAY 0.489362 (-3460 1885);
PAINT MONO (-3460 1885);
FORCEPROP 0 LASTPIN (-3450 1825) $PN AY53
J 2
(-3460 1835);
DISPLAY 0.489362 (-3460 1835);
PAINT MONO (-3460 1835);
FORCEPROP 0 LASTPIN (-3450 1775) $PN BA50
J 2
(-3460 1785);
DISPLAY 0.489362 (-3460 1785);
PAINT MONO (-3460 1785);
FORCEPROP 0 LASTPIN (-3450 1725) $PN BA52
J 2
(-3460 1735);
DISPLAY 0.489362 (-3460 1735);
PAINT MONO (-3460 1735);
FORCEPROP 0 LASTPIN (-3450 1675) $PN BA54
J 2
(-3460 1685);
DISPLAY 0.489362 (-3460 1685);
PAINT MONO (-3460 1685);
FORCEPROP 0 LASTPIN (-3450 1625) $PN BB51
J 2
(-3460 1635);
DISPLAY 0.489362 (-3460 1635);
PAINT MONO (-3460 1635);
FORCEPROP 0 LASTPIN (-3450 1575) $PN BB53
J 2
(-3460 1585);
DISPLAY 0.489362 (-3460 1585);
PAINT MONO (-3460 1585);
FORCEPROP 0 LASTPIN (-3450 1525) $PN BC52
J 2
(-3460 1535);
DISPLAY 0.489362 (-3460 1535);
PAINT MONO (-3460 1535);
FORCEPROP 0 LASTPIN (-3450 1475) $PN BC54
J 2
(-3460 1485);
DISPLAY 0.489362 (-3460 1485);
PAINT MONO (-3460 1485);
FORCEPROP 0 LASTPIN (-3450 875) $PN BN52
J 2
(-3460 885);
DISPLAY 0.489362 (-3460 885);
PAINT MONO (-3460 885);
FORCEPROP 0 LASTPIN (-3450 825) $PN BP51
J 2
(-3460 835);
DISPLAY 0.489362 (-3460 835);
PAINT MONO (-3460 835);
FORCEPROP 0 LASTPIN (-2150 575) $PN BN23
J 0
(-2140 585);
DISPLAY 0.489362 (-2140 585);
PAINT MONO (-2140 585);
FORCEPROP 0 LASTPIN (-2150 5575) $PN AA54
J 0
(-2140 5585);
DISPLAY 0.489362 (-2140 5585);
PAINT MONO (-2140 5585);
FORCEPROP 0 LASTPIN (-2150 5525) $PN AC58
J 0
(-2140 5535);
DISPLAY 0.489362 (-2140 5535);
PAINT MONO (-2140 5535);
FORCEPROP 0 LASTPIN (-2150 5475) $PN AC65
J 0
(-2140 5485);
DISPLAY 0.489362 (-2140 5485);
PAINT MONO (-2140 5485);
FORCEPROP 0 LASTPIN (-2150 5425) $PN AC72
J 0
(-2140 5435);
DISPLAY 0.489362 (-2140 5435);
PAINT MONO (-2140 5435);
FORCEPROP 0 LASTPIN (-2150 5375) $PN AD54
J 0
(-2140 5385);
DISPLAY 0.489362 (-2140 5385);
PAINT MONO (-2140 5385);
FORCEPROP 0 LASTPIN (-2150 5325) $PN AF57
J 0
(-2140 5335);
DISPLAY 0.489362 (-2140 5335);
PAINT MONO (-2140 5335);
FORCEPROP 0 LASTPIN (-2150 5275) $PN AF64
J 0
(-2140 5285);
DISPLAY 0.489362 (-2140 5285);
PAINT MONO (-2140 5285);
FORCEPROP 0 LASTPIN (-2150 5225) $PN AF71
J 0
(-2140 5235);
DISPLAY 0.489362 (-2140 5235);
PAINT MONO (-2140 5235);
FORCEPROP 0 LASTPIN (-2150 5175) $PN AH54
J 0
(-2140 5185);
DISPLAY 0.489362 (-2140 5185);
PAINT MONO (-2140 5185);
FORCEPROP 0 LASTPIN (-2150 5125) $PN AJ58
J 0
(-2140 5135);
DISPLAY 0.489362 (-2140 5135);
PAINT MONO (-2140 5135);
FORCEPROP 0 LASTPIN (-2150 5075) $PN AJ65
J 0
(-2140 5085);
DISPLAY 0.489362 (-2140 5085);
PAINT MONO (-2140 5085);
FORCEPROP 0 LASTPIN (-2150 5025) $PN AJ72
J 0
(-2140 5035);
DISPLAY 0.489362 (-2140 5035);
PAINT MONO (-2140 5035);
FORCEPROP 0 LASTPIN (-2150 4975) $PN AM54
J 0
(-2140 4985);
DISPLAY 0.489362 (-2140 4985);
PAINT MONO (-2140 4985);
FORCEPROP 0 LASTPIN (-2150 4925) $PN AM57
J 0
(-2140 4935);
DISPLAY 0.489362 (-2140 4935);
PAINT MONO (-2140 4935);
FORCEPROP 0 LASTPIN (-2150 4875) $PN AM64
J 0
(-2140 4885);
DISPLAY 0.489362 (-2140 4885);
PAINT MONO (-2140 4885);
FORCEPROP 0 LASTPIN (-2150 4825) $PN AM71
J 0
(-2140 4835);
DISPLAY 0.489362 (-2140 4835);
PAINT MONO (-2140 4835);
FORCEPROP 0 LASTPIN (-2150 4775) $PN AR58
J 0
(-2140 4785);
DISPLAY 0.489362 (-2140 4785);
PAINT MONO (-2140 4785);
FORCEPROP 0 LASTPIN (-2150 4725) $PN AR65
J 0
(-2140 4735);
DISPLAY 0.489362 (-2140 4735);
PAINT MONO (-2140 4735);
FORCEPROP 0 LASTPIN (-2150 4675) $PN AR72
J 0
(-2140 4685);
DISPLAY 0.489362 (-2140 4685);
PAINT MONO (-2140 4685);
FORCEPROP 0 LASTPIN (-3450 2575) $PN BH27
J 2
(-3460 2585);
DISPLAY 0.489362 (-3460 2585);
PAINT MONO (-3460 2585);
FORCEPROP 0 LASTPIN (-2150 4625) $PN AV57
J 0
(-2140 4635);
DISPLAY 0.489362 (-2140 4635);
PAINT MONO (-2140 4635);
FORCEPROP 0 LASTPIN (-2150 4575) $PN AV64
J 0
(-2140 4585);
DISPLAY 0.489362 (-2140 4585);
PAINT MONO (-2140 4585);
FORCEPROP 0 LASTPIN (-2150 4525) $PN AV71
J 0
(-2140 4535);
DISPLAY 0.489362 (-2140 4535);
PAINT MONO (-2140 4535);
FORCEPROP 0 LASTPIN (-2150 4475) $PN BA58
J 0
(-2140 4485);
DISPLAY 0.489362 (-2140 4485);
PAINT MONO (-2140 4485);
FORCEPROP 0 LASTPIN (-2150 4425) $PN BA65
J 0
(-2140 4435);
DISPLAY 0.489362 (-2140 4435);
PAINT MONO (-2140 4435);
FORCEPROP 0 LASTPIN (-2150 4375) $PN BA72
J 0
(-2140 4385);
DISPLAY 0.489362 (-2140 4385);
PAINT MONO (-2140 4385);
FORCEPROP 0 LASTPIN (-2150 4325) $PN BD50
J 0
(-2140 4335);
DISPLAY 0.489362 (-2140 4335);
PAINT MONO (-2140 4335);
FORCEPROP 0 LASTPIN (-2150 4275) $PN BD52
J 0
(-2140 4285);
DISPLAY 0.489362 (-2140 4285);
PAINT MONO (-2140 4285);
FORCEPROP 0 LASTPIN (-2150 4225) $PN BD54
J 0
(-2140 4235);
DISPLAY 0.489362 (-2140 4235);
PAINT MONO (-2140 4235);
FORCEPROP 0 LASTPIN (-2150 4175) $PN BF51
J 0
(-2140 4185);
DISPLAY 0.489362 (-2140 4185);
PAINT MONO (-2140 4185);
FORCEPROP 0 LASTPIN (-2150 4125) $PN BF53
J 0
(-2140 4135);
DISPLAY 0.489362 (-2140 4135);
PAINT MONO (-2140 4135);
FORCEPROP 0 LASTPIN (-2150 4075) $PN BF57
J 0
(-2140 4085);
DISPLAY 0.489362 (-2140 4085);
PAINT MONO (-2140 4085);
FORCEPROP 0 LASTPIN (-2150 4025) $PN BF64
J 0
(-2140 4035);
DISPLAY 0.489362 (-2140 4035);
PAINT MONO (-2140 4035);
FORCEPROP 0 LASTPIN (-2150 3975) $PN BF71
J 0
(-2140 3985);
DISPLAY 0.489362 (-2140 3985);
PAINT MONO (-2140 3985);
FORCEPROP 0 LASTPIN (-2150 3925) $PN BG50
J 0
(-2140 3935);
DISPLAY 0.489362 (-2140 3935);
PAINT MONO (-2140 3935);
FORCEPROP 0 LASTPIN (-2150 3875) $PN BG52
J 0
(-2140 3885);
DISPLAY 0.489362 (-2140 3885);
PAINT MONO (-2140 3885);
FORCEPROP 0 LASTPIN (-2150 3825) $PN BG54
J 0
(-2140 3835);
DISPLAY 0.489362 (-2140 3835);
PAINT MONO (-2140 3835);
FORCEPROP 0 LASTPIN (-2150 3775) $PN BH51
J 0
(-2140 3785);
DISPLAY 0.489362 (-2140 3785);
PAINT MONO (-2140 3785);
FORCEPROP 0 LASTPIN (-2150 3725) $PN BH53
J 0
(-2140 3735);
DISPLAY 0.489362 (-2140 3735);
PAINT MONO (-2140 3735);
FORCEPROP 0 LASTPIN (-2150 3675) $PN BJ50
J 0
(-2140 3685);
DISPLAY 0.489362 (-2140 3685);
PAINT MONO (-2140 3685);
FORCEPROP 0 LASTPIN (-2150 3625) $PN BJ52
J 0
(-2140 3635);
DISPLAY 0.489362 (-2140 3635);
PAINT MONO (-2140 3635);
FORCEPROP 0 LASTPIN (-2150 3575) $PN BJ54
J 0
(-2140 3585);
DISPLAY 0.489362 (-2140 3585);
PAINT MONO (-2140 3585);
FORCEPROP 0 LASTPIN (-2150 3525) $PN BJ58
J 0
(-2140 3535);
DISPLAY 0.489362 (-2140 3535);
PAINT MONO (-2140 3535);
FORCEPROP 0 LASTPIN (-2150 3475) $PN BJ65
J 0
(-2140 3485);
DISPLAY 0.489362 (-2140 3485);
PAINT MONO (-2140 3485);
FORCEPROP 0 LASTPIN (-2150 3425) $PN BJ72
J 0
(-2140 3435);
DISPLAY 0.489362 (-2140 3435);
PAINT MONO (-2140 3435);
FORCEPROP 0 LASTPIN (-2150 3375) $PN BK51
J 0
(-2140 3385);
DISPLAY 0.489362 (-2140 3385);
PAINT MONO (-2140 3385);
FORCEPROP 0 LASTPIN (-2150 3325) $PN BK53
J 0
(-2140 3335);
DISPLAY 0.489362 (-2140 3335);
PAINT MONO (-2140 3335);
FORCEPROP 0 LASTPIN (-2150 3275) $PN BL50
J 0
(-2140 3285);
DISPLAY 0.489362 (-2140 3285);
PAINT MONO (-2140 3285);
FORCEPROP 0 LASTPIN (-2150 3225) $PN BL52
J 0
(-2140 3235);
DISPLAY 0.489362 (-2140 3235);
PAINT MONO (-2140 3235);
FORCEPROP 0 LASTPIN (-2150 3175) $PN BL54
J 0
(-2140 3185);
DISPLAY 0.489362 (-2140 3185);
PAINT MONO (-2140 3185);
FORCEPROP 0 LASTPIN (-2150 3125) $PN BM51
J 0
(-2140 3135);
DISPLAY 0.489362 (-2140 3135);
PAINT MONO (-2140 3135);
FORCEPROP 0 LASTPIN (-2150 3075) $PN BM53
J 0
(-2140 3085);
DISPLAY 0.489362 (-2140 3085);
PAINT MONO (-2140 3085);
FORCEPROP 0 LASTPIN (-2150 3025) $PN BM57
J 0
(-2140 3035);
DISPLAY 0.489362 (-2140 3035);
PAINT MONO (-2140 3035);
FORCEPROP 0 LASTPIN (-2150 2975) $PN BM64
J 0
(-2140 2985);
DISPLAY 0.489362 (-2140 2985);
PAINT MONO (-2140 2985);
FORCEPROP 0 LASTPIN (-2150 2925) $PN BM71
J 0
(-2140 2935);
DISPLAY 0.489362 (-2140 2935);
PAINT MONO (-2140 2935);
FORCEPROP 0 LASTPIN (-2150 2875) $PN BN54
J 0
(-2140 2885);
DISPLAY 0.489362 (-2140 2885);
PAINT MONO (-2140 2885);
FORCEPROP 0 LASTPIN (-2150 2825) $PN BR58
J 0
(-2140 2835);
DISPLAY 0.489362 (-2140 2835);
PAINT MONO (-2140 2835);
FORCEPROP 0 LASTPIN (-2150 2775) $PN BR65
J 0
(-2140 2785);
DISPLAY 0.489362 (-2140 2785);
PAINT MONO (-2140 2785);
FORCEPROP 0 LASTPIN (-2150 2725) $PN BR72
J 0
(-2140 2735);
DISPLAY 0.489362 (-2140 2735);
PAINT MONO (-2140 2735);
FORCEPROP 0 LASTPIN (-2150 2675) $PN BV54
J 0
(-2140 2685);
DISPLAY 0.489362 (-2140 2685);
PAINT MONO (-2140 2685);
FORCEPROP 0 LASTPIN (-2150 2625) $PN BV57
J 0
(-2140 2635);
DISPLAY 0.489362 (-2140 2635);
PAINT MONO (-2140 2635);
FORCEPROP 0 LASTPIN (-2150 2575) $PN BV64
J 0
(-2140 2585);
DISPLAY 0.489362 (-2140 2585);
PAINT MONO (-2140 2585);
FORCEPROP 0 LASTPIN (-2150 2525) $PN BV71
J 0
(-2140 2535);
DISPLAY 0.489362 (-2140 2535);
PAINT MONO (-2140 2535);
FORCEPROP 0 LASTPIN (-2150 2475) $PN CA58
J 0
(-2140 2485);
DISPLAY 0.489362 (-2140 2485);
PAINT MONO (-2140 2485);
FORCEPROP 0 LASTPIN (-2150 2425) $PN CA65
J 0
(-2140 2435);
DISPLAY 0.489362 (-2140 2435);
PAINT MONO (-2140 2435);
FORCEPROP 0 LASTPIN (-2150 2375) $PN CA72
J 0
(-2140 2385);
DISPLAY 0.489362 (-2140 2385);
PAINT MONO (-2140 2385);
FORCEPROP 0 LASTPIN (-2150 2325) $PN CB54
J 0
(-2140 2335);
DISPLAY 0.489362 (-2140 2335);
PAINT MONO (-2140 2335);
FORCEPROP 0 LASTPIN (-2150 2275) $PN CD57
J 0
(-2140 2285);
DISPLAY 0.489362 (-2140 2285);
PAINT MONO (-2140 2285);
FORCEPROP 0 LASTPIN (-2150 2225) $PN CD64
J 0
(-2140 2235);
DISPLAY 0.489362 (-2140 2235);
PAINT MONO (-2140 2235);
FORCEPROP 0 LASTPIN (-2150 2175) $PN CD71
J 0
(-2140 2185);
DISPLAY 0.489362 (-2140 2185);
PAINT MONO (-2140 2185);
FORCEPROP 0 LASTPIN (-2150 2125) $PN CF54
J 0
(-2140 2135);
DISPLAY 0.489362 (-2140 2135);
PAINT MONO (-2140 2135);
FORCEPROP 0 LASTPIN (-2150 2075) $PN CG58
J 0
(-2140 2085);
DISPLAY 0.489362 (-2140 2085);
PAINT MONO (-2140 2085);
FORCEPROP 0 LASTPIN (-2150 2025) $PN CG65
J 0
(-2140 2035);
DISPLAY 0.489362 (-2140 2035);
PAINT MONO (-2140 2035);
FORCEPROP 0 LASTPIN (-2150 1975) $PN CG72
J 0
(-2140 1985);
DISPLAY 0.489362 (-2140 1985);
PAINT MONO (-2140 1985);
FORCEPROP 0 LASTPIN (-2150 1925) $PN CJ54
J 0
(-2140 1935);
DISPLAY 0.489362 (-2140 1935);
PAINT MONO (-2140 1935);
FORCEPROP 0 LASTPIN (-2150 1875) $PN CK57
J 0
(-2140 1885);
DISPLAY 0.489362 (-2140 1885);
PAINT MONO (-2140 1885);
FORCEPROP 0 LASTPIN (-2150 1825) $PN CK64
J 0
(-2140 1835);
DISPLAY 0.489362 (-2140 1835);
PAINT MONO (-2140 1835);
FORCEPROP 0 LASTPIN (-2150 1775) $PN CK71
J 0
(-2140 1785);
DISPLAY 0.489362 (-2140 1785);
PAINT MONO (-2140 1785);
FORCEPROP 0 LASTPIN (-2150 1725) $PN CM54
J 0
(-2140 1735);
DISPLAY 0.489362 (-2140 1735);
PAINT MONO (-2140 1735);
FORCEPROP 0 LASTPIN (-2150 1675) $PN CN58
J 0
(-2140 1685);
DISPLAY 0.489362 (-2140 1685);
PAINT MONO (-2140 1685);
FORCEPROP 0 LASTPIN (-2150 1625) $PN CN65
J 0
(-2140 1635);
DISPLAY 0.489362 (-2140 1635);
PAINT MONO (-2140 1635);
FORCEPROP 0 LASTPIN (-2150 1575) $PN CN72
J 0
(-2140 1585);
DISPLAY 0.489362 (-2140 1585);
PAINT MONO (-2140 1585);
FORCEPROP 0 LASTPIN (-2150 1525) $PN CT54
J 0
(-2140 1535);
DISPLAY 0.489362 (-2140 1535);
PAINT MONO (-2140 1535);
FORCEPROP 0 LASTPIN (-2150 1475) $PN CT57
J 0
(-2140 1485);
DISPLAY 0.489362 (-2140 1485);
PAINT MONO (-2140 1485);
FORCEPROP 0 LASTPIN (-2150 1425) $PN CT64
J 0
(-2140 1435);
DISPLAY 0.489362 (-2140 1435);
PAINT MONO (-2140 1435);
FORCEPROP 0 LASTPIN (-2150 1375) $PN CT71
J 0
(-2140 1385);
DISPLAY 0.489362 (-2140 1385);
PAINT MONO (-2140 1385);
FORCEPROP 0 LASTPIN (-2150 1325) $PN CW58
J 0
(-2140 1335);
DISPLAY 0.489362 (-2140 1335);
PAINT MONO (-2140 1335);
FORCEPROP 0 LASTPIN (-2150 1275) $PN CW65
J 0
(-2140 1285);
DISPLAY 0.489362 (-2140 1285);
PAINT MONO (-2140 1285);
FORCEPROP 0 LASTPIN (-2150 1225) $PN CW72
J 0
(-2140 1235);
DISPLAY 0.489362 (-2140 1235);
PAINT MONO (-2140 1235);
FORCEPROP 0 LASTPIN (-2150 1175) $PN CY54
J 0
(-2140 1185);
DISPLAY 0.489362 (-2140 1185);
PAINT MONO (-2140 1185);
FORCEPROP 0 LASTPIN (-2150 1125) $PN DB57
J 0
(-2140 1135);
DISPLAY 0.489362 (-2140 1135);
PAINT MONO (-2140 1135);
FORCEPROP 0 LASTPIN (-2150 1075) $PN DB64
J 0
(-2140 1085);
DISPLAY 0.489362 (-2140 1085);
PAINT MONO (-2140 1085);
FORCEPROP 0 LASTPIN (-2150 1025) $PN DB71
J 0
(-2140 1035);
DISPLAY 0.489362 (-2140 1035);
PAINT MONO (-2140 1035);
FORCEPROP 0 LASTPIN (-2150 975) $PN DE58
J 0
(-2140 985);
DISPLAY 0.489362 (-2140 985);
PAINT MONO (-2140 985);
FORCEPROP 0 LASTPIN (-2150 925) $PN DE65
J 0
(-2140 935);
DISPLAY 0.489362 (-2140 935);
PAINT MONO (-2140 935);
FORCEPROP 0 LASTPIN (-2150 875) $PN DE72
J 0
(-2140 885);
DISPLAY 0.489362 (-2140 885);
PAINT MONO (-2140 885);
FORCEPROP 0 LASTPIN (-2150 825) $PN DG64
J 0
(-2140 835);
DISPLAY 0.489362 (-2140 835);
PAINT MONO (-2140 835);
FORCEPROP 0 LASTPIN (-2150 775) $PN DG71
J 0
(-2140 785);
DISPLAY 0.489362 (-2140 785);
PAINT MONO (-2140 785);
FORCEPROP 0 LASTPIN (-2150 6475) $PN H57
J 0
(-2140 6485);
DISPLAY 0.489362 (-2140 6485);
PAINT MONO (-2140 6485);
FORCEPROP 0 LASTPIN (-2150 6425) $PN H64
J 0
(-2140 6435);
DISPLAY 0.489362 (-2140 6435);
PAINT MONO (-2140 6435);
FORCEPROP 0 LASTPIN (-2150 6375) $PN H71
J 0
(-2140 6385);
DISPLAY 0.489362 (-2140 6385);
PAINT MONO (-2140 6385);
FORCEPROP 0 LASTPIN (-2150 6325) $PN K54
J 0
(-2140 6335);
DISPLAY 0.489362 (-2140 6335);
PAINT MONO (-2140 6335);
FORCEPROP 0 LASTPIN (-2150 6275) $PN L58
J 0
(-2140 6285);
DISPLAY 0.489362 (-2140 6285);
PAINT MONO (-2140 6285);
FORCEPROP 0 LASTPIN (-2150 6225) $PN L65
J 0
(-2140 6235);
DISPLAY 0.489362 (-2140 6235);
PAINT MONO (-2140 6235);
FORCEPROP 0 LASTPIN (-2150 6175) $PN L72
J 0
(-2140 6185);
DISPLAY 0.489362 (-2140 6185);
PAINT MONO (-2140 6185);
FORCEPROP 0 LASTPIN (-2150 6125) $PN P54
J 0
(-2140 6135);
DISPLAY 0.489362 (-2140 6135);
PAINT MONO (-2140 6135);
FORCEPROP 0 LASTPIN (-2150 6075) $PN P57
J 0
(-2140 6085);
DISPLAY 0.489362 (-2140 6085);
PAINT MONO (-2140 6085);
FORCEPROP 0 LASTPIN (-2150 6025) $PN P64
J 0
(-2140 6035);
DISPLAY 0.489362 (-2140 6035);
PAINT MONO (-2140 6035);
FORCEPROP 0 LASTPIN (-2150 5975) $PN P71
J 0
(-2140 5985);
DISPLAY 0.489362 (-2140 5985);
PAINT MONO (-2140 5985);
FORCEPROP 0 LASTPIN (-2150 5925) $PN U58
J 0
(-2140 5935);
DISPLAY 0.489362 (-2140 5935);
PAINT MONO (-2140 5935);
FORCEPROP 0 LASTPIN (-2150 5875) $PN U65
J 0
(-2140 5885);
DISPLAY 0.489362 (-2140 5885);
PAINT MONO (-2140 5885);
FORCEPROP 0 LASTPIN (-2150 5825) $PN U72
J 0
(-2140 5835);
DISPLAY 0.489362 (-2140 5835);
PAINT MONO (-2140 5835);
FORCEPROP 0 LASTPIN (-2150 5775) $PN V54
J 0
(-2140 5785);
DISPLAY 0.489362 (-2140 5785);
PAINT MONO (-2140 5785);
FORCEPROP 0 LASTPIN (-2150 5725) $PN Y57
J 0
(-2140 5735);
DISPLAY 0.489362 (-2140 5735);
PAINT MONO (-2140 5735);
FORCEPROP 0 LASTPIN (-2150 5675) $PN Y64
J 0
(-2140 5685);
DISPLAY 0.489362 (-2140 5685);
PAINT MONO (-2140 5685);
FORCEPROP 0 LASTPIN (-2150 5625) $PN Y71
J 0
(-2140 5635);
DISPLAY 0.489362 (-2140 5635);
PAINT MONO (-2140 5635);
FORCEPROP 2 LAST VALUE SOCKET6096_13568-001
J 0
(-3200 6600);
DISPLAY 0.489362 (-3200 6600);
PAINT SKYBLUE (-3200 6600);
FORCEPROP 2 LAST PART_TYPE SMLF
J 0
(-3200 6675);
DISPLAY 1.021277 (-3200 6675);
FORCEPROP 1 LAST MATERIAL IO
J 0
(-3295 6607);
DISPLAY 0.489362 (-3295 6607);
PAINT SKYBLUE (-3295 6607);
FORCEPROP 1 LAST NEEDS_NO_SIZE TRUE
J 0
(-2800 3500);
DISPLAY 0.723404 (-2800 3500);
PAINT GREEN (-2800 3500);
DISPLAY INVISIBLE (-2800 3500);
FORCEPROP 1 LAST CDS_LMAN_SYM_OUTLINE -500,3075,500,-3075
J 0
(-2800 3500);
DISPLAY 0.468085 (-2800 3500);
PAINT GREEN (-2800 3500);
DISPLAY INVISIBLE (-2800 3500);
FORCEPROP 2 LAST CDS_LIB pure_quanta
J 0
(-2800 3500);
DISPLAY INVISIBLE (-2800 3500);
FORCEPROP 1 LAST PATH I45
J 0
(-2800 3500);
DISPLAY 0.723404 (-2800 3500);
PAINT GREEN (-2800 3500);
DISPLAY INVISIBLE (-2800 3500);
FORCEPROP 1 LAST PART_NUMBER DGA^6000030
J 0
(-3300 6650);
DISPLAY 0.489362 (-3300 6650);
PAINT SKYBLUE (-3300 6650);
DISPLAY INVISIBLE (-3300 6650);
FORCEADD GENOA_SP5..23
(-875 4325);
FORCEPROP 1 LAST LOCATION U26
J 0
(-1425 6525);
DISPLAY 0.489362 (-1425 6525);
PAINT SKYBLUE (-1425 6525);
FORCEPROP 0 LAST $SEC 23
J 0
(-1400 6675);
DISPLAY 0.680851 (-1400 6675);
PAINT MONO (-1400 6675);
DISPLAY INVISIBLE (-1400 6675);
FORCEPROP 0 LAST CDS_SEC 23
J 0
(-1400 6675);
DISPLAY 1.021277 (-1400 6675);
DISPLAY INVISIBLE (-1400 6675);
FORCEPROP 0 LASTPIN (-1575 5675) $PN A31
J 2
(-1585 5685);
DISPLAY 0.489362 (-1585 5685);
PAINT MONO (-1585 5685);
FORCEPROP 0 LASTPIN (-1575 5625) $PN A35
J 2
(-1585 5635);
DISPLAY 0.489362 (-1585 5635);
PAINT MONO (-1585 5635);
FORCEPROP 0 LASTPIN (-1575 5575) $PN A41
J 2
(-1585 5585);
DISPLAY 0.489362 (-1585 5585);
PAINT MONO (-1585 5585);
FORCEPROP 0 LASTPIN (-1575 5525) $PN A42
J 2
(-1585 5535);
DISPLAY 0.489362 (-1585 5535);
PAINT MONO (-1585 5535);
FORCEPROP 0 LASTPIN (-1575 5475) $PN A45
J 2
(-1585 5485);
DISPLAY 0.489362 (-1585 5485);
PAINT MONO (-1585 5485);
FORCEPROP 0 LASTPIN (-1575 5425) $PN A48
J 2
(-1585 5435);
DISPLAY 0.489362 (-1585 5435);
PAINT MONO (-1585 5435);
FORCEPROP 0 LASTPIN (-1575 5375) $PN A50
J 2
(-1585 5385);
DISPLAY 0.489362 (-1585 5385);
PAINT MONO (-1585 5385);
FORCEPROP 0 LASTPIN (-1575 5325) $PN A51
J 2
(-1585 5335);
DISPLAY 0.489362 (-1585 5335);
PAINT MONO (-1585 5335);
FORCEPROP 0 LASTPIN (-1575 5275) $PN A54
J 2
(-1585 5285);
DISPLAY 0.489362 (-1585 5285);
PAINT MONO (-1585 5285);
FORCEPROP 0 LASTPIN (-1575 5225) $PN A55
J 2
(-1585 5235);
DISPLAY 0.489362 (-1585 5235);
PAINT MONO (-1585 5235);
FORCEPROP 0 LASTPIN (-1575 5175) $PN A56
J 2
(-1585 5185);
DISPLAY 0.489362 (-1585 5185);
PAINT MONO (-1585 5185);
FORCEPROP 0 LASTPIN (-1575 5125) $PN A57
J 2
(-1585 5135);
DISPLAY 0.489362 (-1585 5135);
PAINT MONO (-1585 5135);
FORCEPROP 0 LASTPIN (-1575 5075) $PN A59
J 2
(-1585 5085);
DISPLAY 0.489362 (-1585 5085);
PAINT MONO (-1585 5085);
FORCEPROP 0 LASTPIN (-1575 5025) $PN A60
J 2
(-1585 5035);
DISPLAY 0.489362 (-1585 5035);
PAINT MONO (-1585 5035);
FORCEPROP 0 LASTPIN (-1575 4975) $PN B40
J 2
(-1585 4985);
DISPLAY 0.489362 (-1585 4985);
PAINT MONO (-1585 4985);
FORCEPROP 0 LASTPIN (-1575 4075) $PN BD4
J 2
(-1585 4085);
DISPLAY 0.489362 (-1585 4085);
PAINT MONO (-1585 4085);
FORCEPROP 0 LASTPIN (-1575 4025) $PN BD7
J 2
(-1585 4035);
DISPLAY 0.489362 (-1585 4035);
PAINT MONO (-1585 4035);
FORCEPROP 0 LASTPIN (-1575 3975) $PN BD11
J 2
(-1585 3985);
DISPLAY 0.489362 (-1585 3985);
PAINT MONO (-1585 3985);
FORCEPROP 0 LASTPIN (-1575 3925) $PN BD14
J 2
(-1585 3935);
DISPLAY 0.489362 (-1585 3935);
PAINT MONO (-1585 3935);
FORCEPROP 0 LASTPIN (-1575 3875) $PN BD18
J 2
(-1585 3885);
DISPLAY 0.489362 (-1585 3885);
PAINT MONO (-1585 3885);
FORCEPROP 0 LASTPIN (-1575 3825) $PN BD21
J 2
(-1585 3835);
DISPLAY 0.489362 (-1585 3835);
PAINT MONO (-1585 3835);
FORCEPROP 0 LASTPIN (-1575 3775) $PN BD55
J 2
(-1585 3785);
DISPLAY 0.489362 (-1585 3785);
PAINT MONO (-1585 3785);
FORCEPROP 0 LASTPIN (-1575 3725) $PN BD58
J 2
(-1585 3735);
DISPLAY 0.489362 (-1585 3735);
PAINT MONO (-1585 3735);
FORCEPROP 0 LASTPIN (-1575 3675) $PN BD62
J 2
(-1585 3685);
DISPLAY 0.489362 (-1585 3685);
PAINT MONO (-1585 3685);
FORCEPROP 0 LASTPIN (-1575 3625) $PN BD65
J 2
(-1585 3635);
DISPLAY 0.489362 (-1585 3635);
PAINT MONO (-1585 3635);
FORCEPROP 0 LASTPIN (-1575 3575) $PN BD69
J 2
(-1585 3585);
DISPLAY 0.489362 (-1585 3585);
PAINT MONO (-1585 3585);
FORCEPROP 0 LASTPIN (-1575 3525) $PN BD72
J 2
(-1585 3535);
DISPLAY 0.489362 (-1585 3535);
PAINT MONO (-1585 3535);
FORCEPROP 0 LASTPIN (-1575 4925) $PN C31
J 2
(-1585 4935);
DISPLAY 0.489362 (-1585 4935);
PAINT MONO (-1585 4935);
FORCEPROP 0 LASTPIN (-1575 4875) $PN C34
J 2
(-1585 4885);
DISPLAY 0.489362 (-1585 4885);
PAINT MONO (-1585 4885);
FORCEPROP 0 LASTPIN (-1575 4825) $PN C35
J 2
(-1585 4835);
DISPLAY 0.489362 (-1585 4835);
PAINT MONO (-1585 4835);
FORCEPROP 0 LASTPIN (-1575 4775) $PN C53
J 2
(-1585 4785);
DISPLAY 0.489362 (-1585 4785);
PAINT MONO (-1585 4785);
FORCEPROP 0 LASTPIN (-1575 4725) $PN C54
J 2
(-1585 4735);
DISPLAY 0.489362 (-1585 4735);
PAINT MONO (-1585 4735);
FORCEPROP 0 LASTPIN (-1575 4675) $PN D4
J 2
(-1585 4685);
DISPLAY 0.489362 (-1585 4685);
PAINT MONO (-1585 4685);
FORCEPROP 0 LASTPIN (-1575 4625) $PN D8
J 2
(-1585 4635);
DISPLAY 0.489362 (-1585 4635);
PAINT MONO (-1585 4635);
FORCEPROP 0 LASTPIN (-1575 4575) $PN D11
J 2
(-1585 4585);
DISPLAY 0.489362 (-1585 4585);
PAINT MONO (-1585 4585);
FORCEPROP 0 LASTPIN (-1575 4525) $PN D22
J 2
(-1585 4535);
DISPLAY 0.489362 (-1585 4535);
PAINT MONO (-1585 4535);
FORCEPROP 0 LASTPIN (-1575 4475) $PN D34
J 2
(-1585 4485);
DISPLAY 0.489362 (-1585 4485);
PAINT MONO (-1585 4485);
FORCEPROP 0 LASTPIN (-1575 4425) $PN D36
J 2
(-1585 4435);
DISPLAY 0.489362 (-1585 4435);
PAINT MONO (-1585 4435);
FORCEPROP 0 LASTPIN (-1575 4375) $PN D58
J 2
(-1585 4385);
DISPLAY 0.489362 (-1585 4385);
PAINT MONO (-1585 4385);
FORCEPROP 0 LASTPIN (-1575 4325) $PN D62
J 2
(-1585 4335);
DISPLAY 0.489362 (-1585 4335);
PAINT MONO (-1585 4335);
FORCEPROP 0 LASTPIN (-1575 4275) $PN D65
J 2
(-1585 4285);
DISPLAY 0.489362 (-1585 4285);
PAINT MONO (-1585 4285);
FORCEPROP 0 LASTPIN (-1575 4225) $PN D72
J 2
(-1585 4235);
DISPLAY 0.489362 (-1585 4235);
PAINT MONO (-1585 4235);
FORCEPROP 0 LASTPIN (-1575 3475) $PN DG17
J 2
(-1585 3485);
DISPLAY 0.489362 (-1585 3485);
PAINT MONO (-1585 3485);
FORCEPROP 0 LASTPIN (-1575 3425) $PN DH17
J 2
(-1585 3435);
DISPLAY 0.489362 (-1585 3435);
PAINT MONO (-1585 3435);
FORCEPROP 0 LASTPIN (-1575 3375) $PN DH21
J 2
(-1585 3385);
DISPLAY 0.489362 (-1585 3385);
PAINT MONO (-1585 3385);
FORCEPROP 0 LASTPIN (-1575 3325) $PN DJ4
J 2
(-1585 3335);
DISPLAY 0.489362 (-1585 3335);
PAINT MONO (-1585 3335);
FORCEPROP 0 LASTPIN (-1575 4175) $PN E33
J 2
(-1585 4185);
DISPLAY 0.489362 (-1585 4185);
PAINT MONO (-1585 4185);
FORCEPROP 0 LASTPIN (-1575 4125) $PN E36
J 2
(-1585 4135);
DISPLAY 0.489362 (-1585 4135);
PAINT MONO (-1585 4135);
FORCEPROP 0 LASTPIN (-1575 3125) $PN C58
J 2
(-1585 3135);
DISPLAY 0.489362 (-1585 3135);
PAINT MONO (-1585 3135);
FORCEPROP 0 LASTPIN (-1575 2875) $PN DH13
J 2
(-1585 2885);
DISPLAY 0.489362 (-1585 2885);
PAINT MONO (-1585 2885);
FORCEPROP 0 LASTPIN (-1575 2975) $PN DF41
J 2
(-1585 2985);
DISPLAY 0.489362 (-1585 2985);
PAINT MONO (-1585 2985);
FORCEPROP 0 LASTPIN (-1575 3175) $PN C23
J 2
(-1585 3185);
DISPLAY 0.489362 (-1585 3185);
PAINT MONO (-1585 3185);
FORCEPROP 0 LASTPIN (-1575 3075) $PN C59
J 2
(-1585 3085);
DISPLAY 0.489362 (-1585 3085);
PAINT MONO (-1585 3085);
FORCEPROP 0 LASTPIN (-1575 2825) $PN DH14
J 2
(-1585 2835);
DISPLAY 0.489362 (-1585 2835);
PAINT MONO (-1585 2835);
FORCEPROP 0 LASTPIN (-1575 2925) $PN DG42
J 2
(-1585 2935);
DISPLAY 0.489362 (-1585 2935);
PAINT MONO (-1585 2935);
FORCEPROP 0 LASTPIN (-1575 3025) $PN D23
J 2
(-1585 3035);
DISPLAY 0.489362 (-1585 3035);
PAINT MONO (-1585 3035);
FORCEPROP 0 LASTPIN (-1575 2675) $PN B36
J 2
(-1585 2685);
DISPLAY 0.489362 (-1585 2685);
PAINT MONO (-1585 2685);
FORCEPROP 0 LASTPIN (-1575 2775) $PN DJ57
J 2
(-1585 2785);
DISPLAY 0.489362 (-1585 2785);
PAINT MONO (-1585 2785);
FORCEPROP 2 LAST VALUE SOCKET6096_13568-001
J 0
(-1325 6350);
DISPLAY 0.489362 (-1325 6350);
PAINT SKYBLUE (-1325 6350);
FORCEPROP 1 LAST MATERIAL IO
J 0
(-1420 6357);
DISPLAY 0.489362 (-1420 6357);
PAINT SKYBLUE (-1420 6357);
FORCEPROP 2 LAST PART_TYPE SMLF
J 0
(-1425 6450);
DISPLAY 1.021277 (-1425 6450);
FORCEPROP 1 LAST NEEDS_NO_SIZE TRUE
J 0
(-875 4325);
DISPLAY 0.723404 (-875 4325);
PAINT GREEN (-875 4325);
DISPLAY INVISIBLE (-875 4325);
FORCEPROP 1 LAST CDS_LMAN_SYM_OUTLINE -550,2000,550,-2000
J 0
(-875 4325);
DISPLAY 0.468085 (-875 4325);
PAINT GREEN (-875 4325);
DISPLAY INVISIBLE (-875 4325);
FORCEPROP 2 LAST CDS_LIB pure_quanta
J 0
(-875 4325);
DISPLAY INVISIBLE (-875 4325);
FORCEPROP 1 LAST PATH I46
J 0
(-875 4325);
DISPLAY 0.723404 (-875 4325);
PAINT GREEN (-875 4325);
DISPLAY INVISIBLE (-875 4325);
FORCEPROP 1 LAST PART_NUMBER DGA^6000030
J 0
(-1425 6400);
DISPLAY 0.489362 (-1425 6400);
PAINT SKYBLUE (-1425 6400);
DISPLAY INVISIBLE (-1425 6400);
FORCEADD VCC_CORE..1
(-3825 6250);
FORCEPROP 3 LASTPIN (-3825 6200) SIG_NAME PVDDCR_SOC_P1\g
J 0
(-3815 6210);
DISPLAY 0.659574 (-3815 6210);
PAINT MONO (-3815 6210);
DISPLAY INVISIBLE (-3815 6210);
FORCEPROP 1 LAST HDL_POWER PVDDCR_SOC_P1
J 1
(-3825 6300);
DISPLAY 0.489362 (-3825 6300);
PAINT GREEN (-3825 6300);
FORCEPROP 2 LAST CDS_LIB pure_quanta_power
J 0
(-3825 6250);
DISPLAY INVISIBLE (-3825 6250);
FORCEPROP 1 LAST PATH I47
J 0
(-3775 6275);
DISPLAY 0.872340 (-3775 6275);
PAINT AQUA (-3775 6275);
DISPLAY INVISIBLE (-3775 6275);
FORCEADD VCC_CORE..1
(-5125 6250);
FORCEPROP 3 LASTPIN (-5125 6200) SIG_NAME PVDDCR_SOC_P1\g
J 0
(-5115 6210);
DISPLAY 0.659574 (-5115 6210);
PAINT MONO (-5115 6210);
DISPLAY INVISIBLE (-5115 6210);
FORCEPROP 1 LAST HDL_POWER PVDDCR_SOC_P1
J 1
(-5125 6300);
DISPLAY 0.489362 (-5125 6300);
PAINT GREEN (-5125 6300);
FORCEPROP 2 LAST CDS_LIB pure_quanta_power
J 0
(-5125 6250);
DISPLAY INVISIBLE (-5125 6250);
FORCEPROP 1 LAST PATH I48
J 0
(-5075 6275);
DISPLAY 0.872340 (-5075 6275);
PAINT AQUA (-5075 6275);
DISPLAY INVISIBLE (-5075 6275);
FORCEADD GENOA_SP5..26
(-4475 4675);
FORCEPROP 1 LAST LOCATION U26
J 0
(-4925 6575);
DISPLAY 0.489362 (-4925 6575);
PAINT SKYBLUE (-4925 6575);
FORCEPROP 0 LAST $SEC 26
J 0
(-4900 6675);
DISPLAY 0.680851 (-4900 6675);
PAINT MONO (-4900 6675);
DISPLAY INVISIBLE (-4900 6675);
FORCEPROP 0 LAST CDS_SEC 26
J 0
(-4900 6675);
DISPLAY 1.021277 (-4900 6675);
DISPLAY INVISIBLE (-4900 6675);
FORCEPROP 0 LASTPIN (-5075 5025) $PN AA22
J 2
(-5085 5035);
DISPLAY 0.489362 (-5085 5035);
PAINT MONO (-5085 5035);
FORCEPROP 0 LASTPIN (-5075 4975) $PN AC4
J 2
(-5085 4985);
DISPLAY 0.489362 (-5085 4985);
PAINT MONO (-5085 4985);
FORCEPROP 0 LASTPIN (-5075 4925) $PN AC11
J 2
(-5085 4935);
DISPLAY 0.489362 (-5085 4935);
PAINT MONO (-5085 4935);
FORCEPROP 0 LASTPIN (-5075 4875) $PN AC18
J 2
(-5085 4885);
DISPLAY 0.489362 (-5085 4885);
PAINT MONO (-5085 4885);
FORCEPROP 0 LASTPIN (-5075 4825) $PN AD22
J 2
(-5085 4835);
DISPLAY 0.489362 (-5085 4835);
PAINT MONO (-5085 4835);
FORCEPROP 0 LASTPIN (-5075 4775) $PN AF5
J 2
(-5085 4785);
DISPLAY 0.489362 (-5085 4785);
PAINT MONO (-5085 4785);
FORCEPROP 0 LASTPIN (-5075 4725) $PN AF12
J 2
(-5085 4735);
DISPLAY 0.489362 (-5085 4735);
PAINT MONO (-5085 4735);
FORCEPROP 0 LASTPIN (-5075 4675) $PN AF19
J 2
(-5085 4685);
DISPLAY 0.489362 (-5085 4685);
PAINT MONO (-5085 4685);
FORCEPROP 0 LASTPIN (-5075 4625) $PN AH22
J 2
(-5085 4635);
DISPLAY 0.489362 (-5085 4635);
PAINT MONO (-5085 4635);
FORCEPROP 0 LASTPIN (-5075 4575) $PN AJ4
J 2
(-5085 4585);
DISPLAY 0.489362 (-5085 4585);
PAINT MONO (-5085 4585);
FORCEPROP 0 LASTPIN (-5075 4525) $PN AJ11
J 2
(-5085 4535);
DISPLAY 0.489362 (-5085 4535);
PAINT MONO (-5085 4535);
FORCEPROP 0 LASTPIN (-5075 4475) $PN AJ18
J 2
(-5085 4485);
DISPLAY 0.489362 (-5085 4485);
PAINT MONO (-5085 4485);
FORCEPROP 0 LASTPIN (-5075 4425) $PN AM5
J 2
(-5085 4435);
DISPLAY 0.489362 (-5085 4435);
PAINT MONO (-5085 4435);
FORCEPROP 0 LASTPIN (-5075 4375) $PN AM12
J 2
(-5085 4385);
DISPLAY 0.489362 (-5085 4385);
PAINT MONO (-5085 4385);
FORCEPROP 0 LASTPIN (-5075 4325) $PN AM19
J 2
(-5085 4335);
DISPLAY 0.489362 (-5085 4335);
PAINT MONO (-5085 4335);
FORCEPROP 0 LASTPIN (-5075 4275) $PN AM22
J 2
(-5085 4285);
DISPLAY 0.489362 (-5085 4285);
PAINT MONO (-5085 4285);
FORCEPROP 0 LASTPIN (-5075 4225) $PN AR4
J 2
(-5085 4235);
DISPLAY 0.489362 (-5085 4235);
PAINT MONO (-5085 4235);
FORCEPROP 0 LASTPIN (-5075 4175) $PN AR11
J 2
(-5085 4185);
DISPLAY 0.489362 (-5085 4185);
PAINT MONO (-5085 4185);
FORCEPROP 0 LASTPIN (-5075 4125) $PN AR18
J 2
(-5085 4135);
DISPLAY 0.489362 (-5085 4135);
PAINT MONO (-5085 4135);
FORCEPROP 0 LASTPIN (-5075 4075) $PN AT22
J 2
(-5085 4085);
DISPLAY 0.489362 (-5085 4085);
PAINT MONO (-5085 4085);
FORCEPROP 0 LASTPIN (-5075 4025) $PN AU23
J 2
(-5085 4035);
DISPLAY 0.489362 (-5085 4035);
PAINT MONO (-5085 4035);
FORCEPROP 0 LASTPIN (-5075 3975) $PN AU27
J 2
(-5085 3985);
DISPLAY 0.489362 (-5085 3985);
PAINT MONO (-5085 3985);
FORCEPROP 0 LASTPIN (-5075 3925) $PN AU31
J 2
(-5085 3935);
DISPLAY 0.489362 (-5085 3935);
PAINT MONO (-5085 3935);
FORCEPROP 0 LASTPIN (-5075 3875) $PN AU35
J 2
(-5085 3885);
DISPLAY 0.489362 (-5085 3885);
PAINT MONO (-5085 3885);
FORCEPROP 0 LASTPIN (-5075 3825) $PN AU40
J 2
(-5085 3835);
DISPLAY 0.489362 (-5085 3835);
PAINT MONO (-5085 3835);
FORCEPROP 0 LASTPIN (-5075 3775) $PN AV5
J 2
(-5085 3785);
DISPLAY 0.489362 (-5085 3785);
PAINT MONO (-5085 3785);
FORCEPROP 0 LASTPIN (-5075 3725) $PN AV12
J 2
(-5085 3735);
DISPLAY 0.489362 (-5085 3735);
PAINT MONO (-5085 3735);
FORCEPROP 0 LASTPIN (-5075 3675) $PN AV19
J 2
(-5085 3685);
DISPLAY 0.489362 (-5085 3685);
PAINT MONO (-5085 3685);
FORCEPROP 0 LASTPIN (-5075 3625) $PN AV22
J 2
(-5085 3635);
DISPLAY 0.489362 (-5085 3635);
PAINT MONO (-5085 3635);
FORCEPROP 0 LASTPIN (-5075 3575) $PN AV24
J 2
(-5085 3585);
DISPLAY 0.489362 (-5085 3585);
PAINT MONO (-5085 3585);
FORCEPROP 0 LASTPIN (-5075 3525) $PN AV26
J 2
(-5085 3535);
DISPLAY 0.489362 (-5085 3535);
PAINT MONO (-5085 3535);
FORCEPROP 0 LASTPIN (-5075 3475) $PN AV28
J 2
(-5085 3485);
DISPLAY 0.489362 (-5085 3485);
PAINT MONO (-5085 3485);
FORCEPROP 0 LASTPIN (-5075 3425) $PN AV30
J 2
(-5085 3435);
DISPLAY 0.489362 (-5085 3435);
PAINT MONO (-5085 3435);
FORCEPROP 0 LASTPIN (-5075 3375) $PN AV32
J 2
(-5085 3385);
DISPLAY 0.489362 (-5085 3385);
PAINT MONO (-5085 3385);
FORCEPROP 0 LASTPIN (-5075 3325) $PN AV34
J 2
(-5085 3335);
DISPLAY 0.489362 (-5085 3335);
PAINT MONO (-5085 3335);
FORCEPROP 0 LASTPIN (-5075 3275) $PN AV36
J 2
(-5085 3285);
DISPLAY 0.489362 (-5085 3285);
PAINT MONO (-5085 3285);
FORCEPROP 0 LASTPIN (-5075 3225) $PN AV39
J 2
(-5085 3235);
DISPLAY 0.489362 (-5085 3235);
PAINT MONO (-5085 3235);
FORCEPROP 0 LASTPIN (-5075 3175) $PN AV41
J 2
(-5085 3185);
DISPLAY 0.489362 (-5085 3185);
PAINT MONO (-5085 3185);
FORCEPROP 0 LASTPIN (-3875 6125) $PN AV43
J 0
(-3865 6135);
DISPLAY 0.489362 (-3865 6135);
PAINT MONO (-3865 6135);
FORCEPROP 0 LASTPIN (-3875 6075) $PN AV45
J 0
(-3865 6085);
DISPLAY 0.489362 (-3865 6085);
PAINT MONO (-3865 6085);
FORCEPROP 0 LASTPIN (-3875 6025) $PN AV47
J 0
(-3865 6035);
DISPLAY 0.489362 (-3865 6035);
PAINT MONO (-3865 6035);
FORCEPROP 0 LASTPIN (-3875 5975) $PN AW23
J 0
(-3865 5985);
DISPLAY 0.489362 (-3865 5985);
PAINT MONO (-3865 5985);
FORCEPROP 0 LASTPIN (-3875 5925) $PN AW25
J 0
(-3865 5935);
DISPLAY 0.489362 (-3865 5935);
PAINT MONO (-3865 5935);
FORCEPROP 0 LASTPIN (-3875 5875) $PN AW27
J 0
(-3865 5885);
DISPLAY 0.489362 (-3865 5885);
PAINT MONO (-3865 5885);
FORCEPROP 0 LASTPIN (-3875 5825) $PN AW48
J 0
(-3865 5835);
DISPLAY 0.489362 (-3865 5835);
PAINT MONO (-3865 5835);
FORCEPROP 0 LASTPIN (-3875 5775) $PN AY22
J 0
(-3865 5785);
DISPLAY 0.489362 (-3865 5785);
PAINT MONO (-3865 5785);
FORCEPROP 0 LASTPIN (-3875 5725) $PN AY24
J 0
(-3865 5735);
DISPLAY 0.489362 (-3865 5735);
PAINT MONO (-3865 5735);
FORCEPROP 0 LASTPIN (-3875 5675) $PN AY26
J 0
(-3865 5685);
DISPLAY 0.489362 (-3865 5685);
PAINT MONO (-3865 5685);
FORCEPROP 0 LASTPIN (-3875 5625) $PN AY28
J 0
(-3865 5635);
DISPLAY 0.489362 (-3865 5635);
PAINT MONO (-3865 5635);
FORCEPROP 0 LASTPIN (-3875 5575) $PN AY49
J 0
(-3865 5585);
DISPLAY 0.489362 (-3865 5585);
PAINT MONO (-3865 5585);
FORCEPROP 0 LASTPIN (-5075 6125) $PN B5
J 2
(-5085 6135);
DISPLAY 0.489362 (-5085 6135);
PAINT MONO (-5085 6135);
FORCEPROP 0 LASTPIN (-3875 5525) $PN BA4
J 0
(-3865 5535);
DISPLAY 0.489362 (-3865 5535);
PAINT MONO (-3865 5535);
FORCEPROP 0 LASTPIN (-3875 5475) $PN BA11
J 0
(-3865 5485);
DISPLAY 0.489362 (-3865 5485);
PAINT MONO (-3865 5485);
FORCEPROP 0 LASTPIN (-3875 5425) $PN BA18
J 0
(-3865 5435);
DISPLAY 0.489362 (-3865 5435);
PAINT MONO (-3865 5435);
FORCEPROP 0 LASTPIN (-3875 5375) $PN BA23
J 0
(-3865 5385);
DISPLAY 0.489362 (-3865 5385);
PAINT MONO (-3865 5385);
FORCEPROP 0 LASTPIN (-3875 5325) $PN BA25
J 0
(-3865 5335);
DISPLAY 0.489362 (-3865 5335);
PAINT MONO (-3865 5335);
FORCEPROP 0 LASTPIN (-3875 5275) $PN BA27
J 0
(-3865 5285);
DISPLAY 0.489362 (-3865 5285);
PAINT MONO (-3865 5285);
FORCEPROP 0 LASTPIN (-3875 5225) $PN BA48
J 0
(-3865 5235);
DISPLAY 0.489362 (-3865 5235);
PAINT MONO (-3865 5235);
FORCEPROP 0 LASTPIN (-3875 5175) $PN BB22
J 0
(-3865 5185);
DISPLAY 0.489362 (-3865 5185);
PAINT MONO (-3865 5185);
FORCEPROP 0 LASTPIN (-3875 5125) $PN BB24
J 0
(-3865 5135);
DISPLAY 0.489362 (-3865 5135);
PAINT MONO (-3865 5135);
FORCEPROP 0 LASTPIN (-3875 5075) $PN BB26
J 0
(-3865 5085);
DISPLAY 0.489362 (-3865 5085);
PAINT MONO (-3865 5085);
FORCEPROP 0 LASTPIN (-3875 5025) $PN BB28
J 0
(-3865 5035);
DISPLAY 0.489362 (-3865 5035);
PAINT MONO (-3865 5035);
FORCEPROP 0 LASTPIN (-3875 4975) $PN BB49
J 0
(-3865 4985);
DISPLAY 0.489362 (-3865 4985);
PAINT MONO (-3865 4985);
FORCEPROP 0 LASTPIN (-3875 4925) $PN BC23
J 0
(-3865 4935);
DISPLAY 0.489362 (-3865 4935);
PAINT MONO (-3865 4935);
FORCEPROP 0 LASTPIN (-3875 4875) $PN BC25
J 0
(-3865 4885);
DISPLAY 0.489362 (-3865 4885);
PAINT MONO (-3865 4885);
FORCEPROP 0 LASTPIN (-3875 4825) $PN BC27
J 0
(-3865 4835);
DISPLAY 0.489362 (-3865 4835);
PAINT MONO (-3865 4835);
FORCEPROP 0 LASTPIN (-3875 4775) $PN BC48
J 0
(-3865 4785);
DISPLAY 0.489362 (-3865 4785);
PAINT MONO (-3865 4785);
FORCEPROP 0 LASTPIN (-3875 4725) $PN BD5
J 0
(-3865 4735);
DISPLAY 0.489362 (-3865 4735);
PAINT MONO (-3865 4735);
FORCEPROP 0 LASTPIN (-3875 4675) $PN BD12
J 0
(-3865 4685);
DISPLAY 0.489362 (-3865 4685);
PAINT MONO (-3865 4685);
FORCEPROP 0 LASTPIN (-3875 4625) $PN BD19
J 0
(-3865 4635);
DISPLAY 0.489362 (-3865 4635);
PAINT MONO (-3865 4635);
FORCEPROP 0 LASTPIN (-3875 4575) $PN BD22
J 0
(-3865 4585);
DISPLAY 0.489362 (-3865 4585);
PAINT MONO (-3865 4585);
FORCEPROP 0 LASTPIN (-3875 4525) $PN BD24
J 0
(-3865 4535);
DISPLAY 0.489362 (-3865 4535);
PAINT MONO (-3865 4535);
FORCEPROP 0 LASTPIN (-3875 4475) $PN BD26
J 0
(-3865 4485);
DISPLAY 0.489362 (-3865 4485);
PAINT MONO (-3865 4485);
FORCEPROP 0 LASTPIN (-3875 4425) $PN BD28
J 0
(-3865 4435);
DISPLAY 0.489362 (-3865 4435);
PAINT MONO (-3865 4435);
FORCEPROP 0 LASTPIN (-3875 4375) $PN BD48
J 0
(-3865 4385);
DISPLAY 0.489362 (-3865 4385);
PAINT MONO (-3865 4385);
FORCEPROP 0 LASTPIN (-3875 4325) $PN BF23
J 0
(-3865 4335);
DISPLAY 0.489362 (-3865 4335);
PAINT MONO (-3865 4335);
FORCEPROP 0 LASTPIN (-3875 4275) $PN BF25
J 0
(-3865 4285);
DISPLAY 0.489362 (-3865 4285);
PAINT MONO (-3865 4285);
FORCEPROP 0 LASTPIN (-3875 4225) $PN BF27
J 0
(-3865 4235);
DISPLAY 0.489362 (-3865 4235);
PAINT MONO (-3865 4235);
FORCEPROP 0 LASTPIN (-3875 4175) $PN BF48
J 0
(-3865 4185);
DISPLAY 0.489362 (-3865 4185);
PAINT MONO (-3865 4185);
FORCEPROP 0 LASTPIN (-3875 4125) $PN BG22
J 0
(-3865 4135);
DISPLAY 0.489362 (-3865 4135);
PAINT MONO (-3865 4135);
FORCEPROP 0 LASTPIN (-3875 4075) $PN BG24
J 0
(-3865 4085);
DISPLAY 0.489362 (-3865 4085);
PAINT MONO (-3865 4085);
FORCEPROP 0 LASTPIN (-3875 4025) $PN BG26
J 0
(-3865 4035);
DISPLAY 0.489362 (-3865 4035);
PAINT MONO (-3865 4035);
FORCEPROP 0 LASTPIN (-3875 3975) $PN BG28
J 0
(-3865 3985);
DISPLAY 0.489362 (-3865 3985);
PAINT MONO (-3865 3985);
FORCEPROP 0 LASTPIN (-3875 3925) $PN BG48
J 0
(-3865 3935);
DISPLAY 0.489362 (-3865 3935);
PAINT MONO (-3865 3935);
FORCEPROP 0 LASTPIN (-3875 3875) $PN BH23
J 0
(-3865 3885);
DISPLAY 0.489362 (-3865 3885);
PAINT MONO (-3865 3885);
FORCEPROP 0 LASTPIN (-3875 3825) $PN BH25
J 0
(-3865 3835);
DISPLAY 0.489362 (-3865 3835);
PAINT MONO (-3865 3835);
FORCEPROP 0 LASTPIN (-3875 3775) $PN BH48
J 0
(-3865 3785);
DISPLAY 0.489362 (-3865 3785);
PAINT MONO (-3865 3785);
FORCEPROP 0 LASTPIN (-3875 3725) $PN BJ4
J 0
(-3865 3735);
DISPLAY 0.489362 (-3865 3735);
PAINT MONO (-3865 3735);
FORCEPROP 0 LASTPIN (-3875 3675) $PN BJ11
J 0
(-3865 3685);
DISPLAY 0.489362 (-3865 3685);
PAINT MONO (-3865 3685);
FORCEPROP 0 LASTPIN (-3875 3625) $PN BJ48
J 0
(-3865 3635);
DISPLAY 0.489362 (-3865 3635);
PAINT MONO (-3865 3635);
FORCEPROP 0 LASTPIN (-3875 3575) $PN BM5
J 0
(-3865 3585);
DISPLAY 0.489362 (-3865 3585);
PAINT MONO (-3865 3585);
FORCEPROP 0 LASTPIN (-5075 6075) $PN C4
J 2
(-5085 6085);
DISPLAY 0.489362 (-5085 6085);
PAINT MONO (-5085 6085);
FORCEPROP 0 LASTPIN (-5075 6025) $PN E4
J 2
(-5085 6035);
DISPLAY 0.489362 (-5085 6035);
PAINT MONO (-5085 6035);
FORCEPROP 0 LASTPIN (-5075 5975) $PN E11
J 2
(-5085 5985);
DISPLAY 0.489362 (-5085 5985);
PAINT MONO (-5085 5985);
FORCEPROP 0 LASTPIN (-5075 5925) $PN H5
J 2
(-5085 5935);
DISPLAY 0.489362 (-5085 5935);
PAINT MONO (-5085 5935);
FORCEPROP 0 LASTPIN (-5075 5875) $PN H12
J 2
(-5085 5885);
DISPLAY 0.489362 (-5085 5885);
PAINT MONO (-5085 5885);
FORCEPROP 0 LASTPIN (-5075 5825) $PN H19
J 2
(-5085 5835);
DISPLAY 0.489362 (-5085 5835);
PAINT MONO (-5085 5835);
FORCEPROP 0 LASTPIN (-5075 5775) $PN K22
J 2
(-5085 5785);
DISPLAY 0.489362 (-5085 5785);
PAINT MONO (-5085 5785);
FORCEPROP 0 LASTPIN (-5075 5725) $PN L4
J 2
(-5085 5735);
DISPLAY 0.489362 (-5085 5735);
PAINT MONO (-5085 5735);
FORCEPROP 0 LASTPIN (-5075 5675) $PN L11
J 2
(-5085 5685);
DISPLAY 0.489362 (-5085 5685);
PAINT MONO (-5085 5685);
FORCEPROP 0 LASTPIN (-5075 5625) $PN L18
J 2
(-5085 5635);
DISPLAY 0.489362 (-5085 5635);
PAINT MONO (-5085 5635);
FORCEPROP 0 LASTPIN (-5075 5575) $PN P5
J 2
(-5085 5585);
DISPLAY 0.489362 (-5085 5585);
PAINT MONO (-5085 5585);
FORCEPROP 0 LASTPIN (-5075 5525) $PN P12
J 2
(-5085 5535);
DISPLAY 0.489362 (-5085 5535);
PAINT MONO (-5085 5535);
FORCEPROP 0 LASTPIN (-5075 5475) $PN P19
J 2
(-5085 5485);
DISPLAY 0.489362 (-5085 5485);
PAINT MONO (-5085 5485);
FORCEPROP 0 LASTPIN (-5075 5425) $PN P22
J 2
(-5085 5435);
DISPLAY 0.489362 (-5085 5435);
PAINT MONO (-5085 5435);
FORCEPROP 0 LASTPIN (-5075 5375) $PN U4
J 2
(-5085 5385);
DISPLAY 0.489362 (-5085 5385);
PAINT MONO (-5085 5385);
FORCEPROP 0 LASTPIN (-5075 5325) $PN U11
J 2
(-5085 5335);
DISPLAY 0.489362 (-5085 5335);
PAINT MONO (-5085 5335);
FORCEPROP 0 LASTPIN (-5075 5275) $PN U18
J 2
(-5085 5285);
DISPLAY 0.489362 (-5085 5285);
PAINT MONO (-5085 5285);
FORCEPROP 0 LASTPIN (-5075 5225) $PN V22
J 2
(-5085 5235);
DISPLAY 0.489362 (-5085 5235);
PAINT MONO (-5085 5235);
FORCEPROP 0 LASTPIN (-5075 5175) $PN Y5
J 2
(-5085 5185);
DISPLAY 0.489362 (-5085 5185);
PAINT MONO (-5085 5185);
FORCEPROP 0 LASTPIN (-5075 5125) $PN Y12
J 2
(-5085 5135);
DISPLAY 0.489362 (-5085 5135);
PAINT MONO (-5085 5135);
FORCEPROP 0 LASTPIN (-5075 5075) $PN Y19
J 2
(-5085 5085);
DISPLAY 0.489362 (-5085 5085);
PAINT MONO (-5085 5085);
FORCEPROP 2 LAST VALUE SOCKET6096_13568-001
J 0
(-4925 6425);
DISPLAY 0.489362 (-4925 6425);
PAINT SKYBLUE (-4925 6425);
FORCEPROP 1 LAST MATERIAL IO
J 0
(-4920 6357);
DISPLAY 0.489362 (-4920 6357);
PAINT SKYBLUE (-4920 6357);
FORCEPROP 2 LAST PART_TYPE SMLF
J 0
(-4925 6525);
DISPLAY 1.021277 (-4925 6525);
FORCEPROP 1 LAST NEEDS_NO_SIZE TRUE
J 0
(-4475 4675);
DISPLAY 0.723404 (-4475 4675);
PAINT GREEN (-4475 4675);
DISPLAY INVISIBLE (-4475 4675);
FORCEPROP 1 LAST CDS_LMAN_SYM_OUTLINE -450,1650,450,-1650
J 0
(-4475 4675);
DISPLAY 0.468085 (-4475 4675);
PAINT GREEN (-4475 4675);
DISPLAY INVISIBLE (-4475 4675);
FORCEPROP 2 LAST CDS_LIB pure_quanta
J 0
(-4475 4675);
DISPLAY INVISIBLE (-4475 4675);
FORCEPROP 1 LAST PATH I49
J 0
(-4475 4675);
DISPLAY 0.723404 (-4475 4675);
PAINT GREEN (-4475 4675);
DISPLAY INVISIBLE (-4475 4675);
FORCEPROP 1 LAST PART_NUMBER DGA^6000030
J 0
(-4920 6484);
DISPLAY 0.489362 (-4920 6484);
PAINT SKYBLUE (-4920 6484);
DISPLAY INVISIBLE (-4920 6484);
FORCEADD Q_RES..2
(-1125 725);
FORCEPROP 1 LAST LOCATION R374
J 0
(-1075 800);
DISPLAY 0.489362 (-1075 800);
PAINT SKYBLUE (-1075 800);
FORCEPROP 0 LAST $SEC 1
J 0
(-1075 850);
DISPLAY 0.680851 (-1075 850);
PAINT MONO (-1075 850);
DISPLAY INVISIBLE (-1075 850);
FORCEPROP 0 LAST CDS_SEC 1
J 0
(-1075 850);
DISPLAY 1.021277 (-1075 850);
DISPLAY INVISIBLE (-1075 850);
FORCEPROP 1 LASTPIN (-1125 825) $PN 1
J 0
(-1120 787);
DISPLAY 0.489362 (-1120 787);
PAINT MONO (-1120 787);
FORCEPROP 1 LASTPIN (-1125 625) $PN 2
J 0
(-1120 635);
DISPLAY 0.489362 (-1120 635);
PAINT MONO (-1120 635);
FORCEPROP 1 LAST WATTAGE 1/16W
J 0
(-1075 725);
DISPLAY 0.489362 (-1075 725);
PAINT SKYBLUE (-1075 725);
FORCEPROP 1 LAST MATERIAL CHIP
J 0
(-1075 700);
DISPLAY 0.489362 (-1075 700);
PAINT SKYBLUE (-1075 700);
FORCEPROP 1 LAST TOLERANCE 5%
J 0
(-1075 750);
DISPLAY 0.489362 (-1075 750);
PAINT SKYBLUE (-1075 750);
FORCEPROP 1 LAST VALUE 0
J 0
(-1075 775);
DISPLAY 0.489362 (-1075 775);
PAINT SKYBLUE (-1075 775);
FORCEPROP 1 LAST PACK_TYPE 0402LF
J 0
(-1075 675);
DISPLAY 0.489362 (-1075 675);
PAINT SKYBLUE (-1075 675);
FORCEPROP 2 LAST BOM_COST MEM
R 3
J 0
(-1250 650);
DISPLAY 0.574468 (-1250 650);
PAINT WHITE (-1250 650);
DISPLAY INVISIBLE (-1250 650);
FORCEPROP 2 LAST CDS_LIB pure_quanta
J 0
(-1125 725);
DISPLAY INVISIBLE (-1125 725);
FORCEPROP 1 LAST PATH I51
J 0
(-1075 900);
DISPLAY 0.978723 (-1075 900);
PAINT WHITE (-1075 900);
DISPLAY INVISIBLE (-1075 900);
FORCEPROP 1 LAST PART_NUMBER CS00002JB13
J 0
(-1075 675);
DISPLAY 0.489362 (-1075 675);
PAINT SKYBLUE (-1075 675);
DISPLAY INVISIBLE (-1075 675);
FORCEADD Q_RES..2
(-1450 725);
FORCEPROP 1 LAST LOCATION R373
J 0
(-1425 800);
DISPLAY 0.489362 (-1425 800);
PAINT SKYBLUE (-1425 800);
FORCEPROP 0 LAST $SEC 1
J 0
(-1425 850);
DISPLAY 0.680851 (-1425 850);
PAINT MONO (-1425 850);
DISPLAY INVISIBLE (-1425 850);
FORCEPROP 0 LAST CDS_SEC 1
J 0
(-1425 850);
DISPLAY 1.021277 (-1425 850);
DISPLAY INVISIBLE (-1425 850);
FORCEPROP 1 LASTPIN (-1450 825) $PN 1
J 0
(-1445 787);
DISPLAY 0.489362 (-1445 787);
PAINT MONO (-1445 787);
FORCEPROP 1 LASTPIN (-1450 625) $PN 2
J 0
(-1445 635);
DISPLAY 0.489362 (-1445 635);
PAINT MONO (-1445 635);
FORCEPROP 1 LAST WATTAGE 1/16W
J 0
(-1400 725);
DISPLAY 0.489362 (-1400 725);
PAINT SKYBLUE (-1400 725);
FORCEPROP 1 LAST MATERIAL EMPTY
J 0
(-1400 700);
DISPLAY 0.489362 (-1400 700);
PAINT RED (-1400 700);
FORCEPROP 1 LAST TOLERANCE 5%
J 0
(-1400 750);
DISPLAY 0.489362 (-1400 750);
PAINT SKYBLUE (-1400 750);
FORCEPROP 1 LAST VALUE 0
J 0
(-1400 775);
DISPLAY 0.489362 (-1400 775);
PAINT SKYBLUE (-1400 775);
FORCEPROP 1 LAST PACK_TYPE 0402LF
J 0
(-1400 650);
DISPLAY 0.489362 (-1400 650);
PAINT SKYBLUE (-1400 650);
FORCEPROP 2 LAST BOM_COST MEM
R 3
J 0
(-1575 650);
DISPLAY 0.574468 (-1575 650);
PAINT WHITE (-1575 650);
DISPLAY INVISIBLE (-1575 650);
FORCEPROP 2 LAST CDS_LIB pure_quanta
J 0
(-1450 725);
DISPLAY INVISIBLE (-1450 725);
FORCEPROP 1 LAST PATH I52
J 0
(-1400 900);
DISPLAY 0.978723 (-1400 900);
PAINT WHITE (-1400 900);
DISPLAY INVISIBLE (-1400 900);
FORCEPROP 1 LAST PART_NUMBER CS00002JB13
J 0
(-1400 675);
DISPLAY 0.489362 (-1400 675);
PAINT SKYBLUE (-1400 675);
DISPLAY INVISIBLE (-1400 675);
FORCEADD QUANTA_TITLE_BLOCK_C..1
(-100 100);
FORCEPROP 0 LAST CDS_CON_LAST_MODIFIED Thu Sep 14 16:12:01 2023
J 0
(-1985 115);
DISPLAY INVISIBLE (-1985 115);
FORCEPROP 1 LAST CUSTOM_TXT_CDS <CON_LAST_MODIFIED>
J 0
(-1985 115);
DISPLAY 0.978723 (-1985 115);
FORCEPROP 2 LAST CUSTOM_TXT_CDS <XR_PAGE_TITLE>
J 0
(-7990 5350);
DISPLAY 0.638298 (-7990 5350);
PAINT PINK (-7990 5350);
DISPLAY INVISIBLE (-7990 5350);
FORCEPROP 1 LAST CUSTOM_TXT_CDS <NAME_2>
J 0
(-3275 150);
FORCEPROP 1 LAST CUSTOM_TXT_CDS <NAME_1>
J 0
(-3275 275);
FORCEPROP 1 LAST CUSTOM_TXT_CDS <Q_NUMBER>
J 0
(-1503 203);
DISPLAY 1.212766 (-1503 203);
FORCEPROP 1 LAST CUSTOM_TXT_CDS <Q_PROJ>
J 0
(-2482 202);
DISPLAY 1.212766 (-2482 202);
FORCEPROP 1 LAST CUSTOM_TXT_CDS <Q_REV>
J 0
(-284 203);
DISPLAY 1.212766 (-284 203);
FORCEPROP 1 LAST CUSTOM_TXT_CDS <CON_PAGE_NUM> OF <CON_TOTAL_PAGES>
J 0
(-546 118);
DISPLAY 0.978723 (-546 118);
FORCEPROP 1 LAST Q_TITLE CPU1 POWER
J 0
(-9400 150);
DISPLAY 1.574468 (-9400 150);
PAINT GREEN (-9400 150);
FORCEPROP 2 LAST CDS_LIB pure_quanta
J 0
(-100 100);
DISPLAY INVISIBLE (-100 100);
FORCEPROP 1 LAST CDS_LMAN_SYM_OUTLINE -9475,6775,100,-125
J 0
(-100 100);
DISPLAY 0.468085 (-100 100);
PAINT GREEN (-100 100);
DISPLAY INVISIBLE (-100 100);
FORCEPROP 2 LAST PAGE_BORDER TRUE
J 0
(-7990 5350);
DISPLAY 0.638298 (-7990 5350);
PAINT PINK (-7990 5350);
DISPLAY INVISIBLE (-7990 5350);
FORCEPROP 2 LAST CDS_XR_PAGE_TITLE CR-57 : @T6G_MB_LIB.T6G(SCH_1):PAGE57
J 0
(-7990 5350);
DISPLAY 0.638298 (-7990 5350);
PAINT PINK (-7990 5350);
DISPLAY INVISIBLE (-7990 5350);
FORCEPROP 1 LAST Q_DEPT BU9
J 1
(-3863 149);
DISPLAY 1.957447 (-3863 149);
PAINT GREEN (-3863 149);
DISPLAY INVISIBLE (-3863 149);
FORCEPROP 1 LAST COMMENT_BODY TRUE
J 0
(-88 87);
DISPLAY 0.978723 (-88 87);
PAINT GREEN (-88 87);
DISPLAY INVISIBLE (-88 87);
FORCEADD DNS..2
(-1425 725);
PAINT RED (-1425 725);
FORCEPROP 2 LAST CDS_LIB mstr_misc
J 0
(-1425 725);
DISPLAY INVISIBLE (-1425 725);
FORCEPROP 1 LAST COMMENT_BODY TRUE
R 1
J 0
(-1350 500);
DISPLAY 0.872340 (-1350 500);
PAINT GREEN (-1350 500);
DISPLAY INVISIBLE (-1350 500);
WIRE 16 -1 (-1125 825)(-1125 900);
WIRE 16 -1 (-1450 825)(-1450 900);
WIRE 16 -1 (-7425 550)(-7500 550);
WIRE 16 -1 (-7425 600)(-7425 550);
WIRE 16 -1 (-7425 650)(-7425 600);
WIRE 16 -1 (-7425 600)(-7500 600);
WIRE 16 -1 (-7425 700)(-7425 650);
WIRE 16 -1 (-7425 650)(-7500 650);
WIRE 16 -1 (-7425 750)(-7425 700);
WIRE 16 -1 (-7425 700)(-7500 700);
WIRE 16 -1 (-7425 800)(-7425 750);
WIRE 16 -1 (-7425 750)(-7500 750);
WIRE 16 -1 (-7425 800)(-7500 800);
WIRE 16 -1 (-7425 850)(-7425 800);
WIRE 16 -1 (-7425 900)(-7425 850);
WIRE 16 -1 (-7425 850)(-7500 850);
WIRE 16 -1 (-7425 900)(-7425 950);
WIRE 16 -1 (-7500 900)(-7425 900);
WIRE 16 -1 (-7425 1000)(-7425 950);
WIRE 16 -1 (-7425 950)(-7500 950);
WIRE 16 -1 (-7425 1050)(-7425 1000);
WIRE 16 -1 (-7425 1000)(-7500 1000);
WIRE 16 -1 (-7425 1100)(-7425 1050);
WIRE 16 -1 (-7425 1050)(-7500 1050);
WIRE 16 -1 (-7425 1150)(-7425 1100);
WIRE 16 -1 (-7425 1100)(-7500 1100);
WIRE 16 -1 (-7425 1200)(-7425 1150);
WIRE 16 -1 (-7425 1150)(-7500 1150);
WIRE 16 -1 (-7425 1200)(-7500 1200);
WIRE 16 -1 (-7425 1250)(-7425 1200);
WIRE 16 -1 (-7425 1300)(-7425 1250);
WIRE 16 -1 (-7425 1250)(-7500 1250);
WIRE 16 -1 (-7425 1350)(-7425 1300);
WIRE 16 -1 (-7425 1300)(-7500 1300);
WIRE 16 -1 (-7425 1350)(-7425 1400);
WIRE 16 -1 (-7500 1350)(-7425 1350);
WIRE 16 -1 (-7425 1450)(-7425 1400);
WIRE 16 -1 (-7425 1400)(-7500 1400);
WIRE 16 -1 (-7425 1450)(-7500 1450);
WIRE 16 -1 (-7425 1500)(-7425 1450);
WIRE 16 -1 (-7425 1550)(-7425 1500);
WIRE 16 -1 (-7425 1500)(-7500 1500);
WIRE 16 -1 (-7425 1600)(-7425 1550);
WIRE 16 -1 (-7425 1550)(-7500 1550);
WIRE 16 -1 (-7425 1650)(-7425 1600);
WIRE 16 -1 (-7425 1600)(-7500 1600);
WIRE 16 -1 (-7425 1700)(-7425 1650);
WIRE 16 -1 (-7425 1650)(-7500 1650);
WIRE 16 -1 (-7425 1700)(-7500 1700);
WIRE 16 -1 (-7425 1750)(-7425 1700);
WIRE 16 -1 (-7425 1800)(-7425 1750);
WIRE 16 -1 (-7425 1750)(-7500 1750);
WIRE 16 -1 (-7425 1800)(-7425 1850);
WIRE 16 -1 (-7500 1800)(-7425 1800);
WIRE 16 -1 (-7425 1900)(-7425 1850);
WIRE 16 -1 (-7425 1850)(-7500 1850);
WIRE 16 -1 (-7425 1950)(-7425 1900);
WIRE 16 -1 (-7425 1900)(-7500 1900);
WIRE 16 -1 (-7425 1950)(-7500 1950);
WIRE 16 -1 (-7425 2000)(-7425 1950);
WIRE 16 -1 (-7425 2050)(-7425 2000);
WIRE 16 -1 (-7425 2000)(-7500 2000);
WIRE 16 -1 (-7425 2100)(-7425 2050);
WIRE 16 -1 (-7425 2050)(-7500 2050);
WIRE 16 -1 (-7425 2150)(-7425 2100);
WIRE 16 -1 (-7425 2100)(-7500 2100);
WIRE 16 -1 (-7425 2200)(-7425 2150);
WIRE 16 -1 (-7425 2150)(-7500 2150);
WIRE 16 -1 (-7425 2250)(-7425 2200);
WIRE 16 -1 (-7425 2200)(-7500 2200);
WIRE 16 -1 (-7425 2250)(-7425 2300);
WIRE 16 -1 (-7500 2250)(-7425 2250);
WIRE 16 -1 (-7425 2350)(-7425 2300);
WIRE 16 -1 (-7425 2300)(-7500 2300);
WIRE 16 -1 (-7425 2350)(-7500 2350);
WIRE 16 -1 (-7425 2400)(-7425 2350);
WIRE 16 -1 (-7425 2450)(-7425 2400);
WIRE 16 -1 (-7425 2400)(-7500 2400);
WIRE 16 -1 (-7425 2500)(-7425 2450);
WIRE 16 -1 (-7425 2450)(-7500 2450);
WIRE 16 -1 (-7425 2550)(-7425 2500);
WIRE 16 -1 (-7425 2500)(-7500 2500);
WIRE 16 -1 (-7425 2600)(-7425 2550);
WIRE 16 -1 (-7425 2550)(-7500 2550);
WIRE 16 -1 (-7425 2600)(-7500 2600);
WIRE 16 -1 (-7425 2650)(-7425 2600);
WIRE 16 -1 (-7425 2700)(-7425 2650);
WIRE 16 -1 (-7425 2650)(-7500 2650);
WIRE 16 -1 (-7425 2700)(-7425 2750);
WIRE 16 -1 (-7500 2700)(-7425 2700);
WIRE 16 -1 (-7425 2800)(-7425 2750);
WIRE 16 -1 (-7425 2750)(-7500 2750);
WIRE 16 -1 (-7425 2850)(-7425 2800);
WIRE 16 -1 (-7425 2800)(-7500 2800);
WIRE 16 -1 (-7425 2850)(-7500 2850);
WIRE 16 -1 (-7425 2900)(-7425 2850);
WIRE 16 -1 (-7425 2950)(-7425 2900);
WIRE 16 -1 (-7425 2900)(-7500 2900);
WIRE 16 -1 (-7425 3000)(-7425 2950);
WIRE 16 -1 (-7425 2950)(-7500 2950);
WIRE 16 -1 (-7425 3050)(-7425 3000);
WIRE 16 -1 (-7425 3000)(-7500 3000);
WIRE 16 -1 (-7425 3100)(-7425 3050);
WIRE 16 -1 (-7425 3050)(-7500 3050);
WIRE 16 -1 (-7425 3100)(-7500 3100);
WIRE 16 -1 (-7425 3150)(-7425 3100);
WIRE 16 -1 (-7425 3150)(-7425 3200);
WIRE 16 -1 (-7500 3150)(-7425 3150);
WIRE 16 -1 (-7425 3200)(-7500 3200);
WIRE 16 -1 (-7425 3250)(-7425 3200);
WIRE 16 -1 (-7425 3250)(-7500 3250);
WIRE 16 -1 (-7425 3300)(-7425 3250);
WIRE 16 -1 (-7425 3350)(-7425 3300);
WIRE 16 -1 (-7425 3300)(-7500 3300);
WIRE 16 -1 (-7425 3400)(-7425 3350);
WIRE 16 -1 (-7425 3350)(-7500 3350);
WIRE 16 -1 (-7425 3450)(-7425 3400);
WIRE 16 -1 (-7425 3400)(-7500 3400);
WIRE 16 -1 (-7425 3500)(-7425 3450);
WIRE 16 -1 (-7425 3450)(-7500 3450);
WIRE 16 -1 (-7425 3500)(-7500 3500);
WIRE 16 -1 (-7425 3550)(-7425 3500);
WIRE 16 -1 (-7425 3600)(-7425 3550);
WIRE 16 -1 (-7425 3550)(-7500 3550);
WIRE 16 -1 (-7425 3600)(-7425 3650);
WIRE 16 -1 (-7500 3600)(-7425 3600);
WIRE 16 -1 (-7425 3700)(-7425 3650);
WIRE 16 -1 (-7425 3650)(-7500 3650);
WIRE 16 -1 (-7425 3750)(-7425 3700);
WIRE 16 -1 (-7425 3700)(-7500 3700);
WIRE 16 -1 (-7425 3750)(-7500 3750);
WIRE 16 -1 (-7425 3800)(-7425 3750);
WIRE 16 -1 (-7425 3850)(-7425 3800);
WIRE 16 -1 (-7425 3800)(-7500 3800);
WIRE 16 -1 (-7425 3900)(-7425 3850);
WIRE 16 -1 (-7425 3850)(-7500 3850);
WIRE 16 -1 (-7425 3950)(-7425 3900);
WIRE 16 -1 (-7425 3900)(-7500 3900);
WIRE 16 -1 (-7425 4000)(-7425 3950);
WIRE 16 -1 (-7425 3950)(-7500 3950);
WIRE 16 -1 (-7425 4000)(-7500 4000);
WIRE 16 -1 (-7425 4050)(-7425 4000);
WIRE 16 -1 (-7425 4050)(-7425 4100);
WIRE 16 -1 (-7500 4050)(-7425 4050);
WIRE 16 -1 (-7425 4150)(-7425 4100);
WIRE 16 -1 (-7425 4100)(-7500 4100);
WIRE 16 -1 (-7425 4200)(-7425 4150);
WIRE 16 -1 (-7425 4150)(-7500 4150);
WIRE 16 -1 (-7425 4250)(-7425 4200);
WIRE 16 -1 (-7425 4200)(-7500 4200);
WIRE 16 -1 (-7425 4300)(-7425 4250);
WIRE 16 -1 (-7425 4250)(-7500 4250);
WIRE 16 -1 (-7425 4350)(-7425 4300);
WIRE 16 -1 (-7425 4300)(-7500 4300);
WIRE 16 -1 (-7425 4400)(-7425 4350);
WIRE 16 -1 (-7425 4350)(-7500 4350);
WIRE 16 -1 (-7425 4400)(-7500 4400);
WIRE 16 -1 (-7425 4450)(-7425 4400);
WIRE 16 -1 (-7425 4500)(-7425 4450);
WIRE 16 -1 (-7425 4450)(-7500 4450);
WIRE 16 -1 (-7425 4500)(-7425 4550);
WIRE 16 -1 (-7500 4500)(-7425 4500);
WIRE 16 -1 (-7425 4600)(-7425 4550);
WIRE 16 -1 (-7425 4550)(-7500 4550);
WIRE 16 -1 (-7425 4650)(-7425 4600);
WIRE 16 -1 (-7425 4600)(-7500 4600);
WIRE 16 -1 (-7425 4650)(-7500 4650);
WIRE 16 -1 (-7425 4700)(-7425 4650);
WIRE 16 -1 (-7425 4750)(-7425 4700);
WIRE 16 -1 (-7425 4700)(-7500 4700);
WIRE 16 -1 (-7425 4800)(-7425 4750);
WIRE 16 -1 (-7425 4750)(-7500 4750);
WIRE 16 -1 (-7425 4850)(-7425 4800);
WIRE 16 -1 (-7425 4800)(-7500 4800);
WIRE 16 -1 (-7425 4900)(-7425 4850);
WIRE 16 -1 (-7425 4850)(-7500 4850);
WIRE 16 -1 (-7425 4900)(-7500 4900);
WIRE 16 -1 (-7425 4950)(-7425 4900);
WIRE 16 -1 (-7425 4950)(-7425 5000);
WIRE 16 -1 (-7500 4950)(-7425 4950);
WIRE 16 -1 (-7425 5050)(-7425 5000);
WIRE 16 -1 (-7425 5000)(-7500 5000);
WIRE 16 -1 (-7425 5100)(-7425 5050);
WIRE 16 -1 (-7425 5050)(-7500 5050);
WIRE 16 -1 (-7425 5150)(-7425 5100);
WIRE 16 -1 (-7425 5100)(-7500 5100);
WIRE 16 -1 (-7425 5150)(-7500 5150);
WIRE 16 -1 (-7425 5200)(-7425 5150);
WIRE 16 -1 (-7425 5250)(-7425 5200);
WIRE 16 -1 (-7425 5200)(-7500 5200);
WIRE 16 -1 (-7425 5300)(-7425 5250);
WIRE 16 -1 (-7425 5250)(-7500 5250);
WIRE 16 -1 (-7425 5350)(-7425 5300);
WIRE 16 -1 (-7425 5300)(-7500 5300);
WIRE 16 -1 (-7425 5400)(-7425 5350);
WIRE 16 -1 (-7425 5350)(-7500 5350);
WIRE 16 -1 (-7425 5400)(-7425 5450);
WIRE 16 -1 (-7500 5400)(-7425 5400);
WIRE 16 -1 (-7425 5500)(-7425 5450);
WIRE 16 -1 (-7425 5450)(-7500 5450);
WIRE 16 -1 (-7425 5550)(-7425 5500);
WIRE 16 -1 (-7425 5500)(-7500 5500);
WIRE 16 -1 (-7425 5550)(-7500 5550);
WIRE 16 -1 (-7425 5600)(-7425 5550);
WIRE 16 -1 (-7425 5650)(-7425 5600);
WIRE 16 -1 (-7425 5600)(-7500 5600);
WIRE 16 -1 (-7425 5700)(-7425 5650);
WIRE 16 -1 (-7425 5650)(-7500 5650);
WIRE 16 -1 (-7425 5750)(-7425 5700);
WIRE 16 -1 (-7425 5700)(-7500 5700);
WIRE 16 -1 (-7425 5800)(-7425 5750);
WIRE 16 -1 (-7425 5750)(-7500 5750);
WIRE 16 -1 (-7425 5800)(-7500 5800);
WIRE 16 -1 (-7425 5850)(-7425 5800);
WIRE 16 -1 (-7425 5850)(-7425 5900);
WIRE 16 -1 (-7500 5850)(-7425 5850);
WIRE 16 -1 (-7425 5950)(-7425 5900);
WIRE 16 -1 (-7425 5900)(-7500 5900);
WIRE 16 -1 (-7425 6000)(-7425 5950);
WIRE 16 -1 (-7425 5950)(-7500 5950);
WIRE 16 -1 (-7425 6050)(-7425 6000);
WIRE 16 -1 (-7425 6000)(-7500 6000);
WIRE 16 -1 (-7425 6050)(-7500 6050);
WIRE 16 -1 (-7425 6100)(-7425 6050);
WIRE 16 -1 (-7425 6150)(-7425 6100);
WIRE 16 -1 (-7425 6100)(-7500 6100);
WIRE 16 -1 (-7425 6200)(-7425 6150);
WIRE 16 -1 (-7425 6150)(-7500 6150);
WIRE 16 -1 (-7425 6250)(-7425 6200);
WIRE 16 -1 (-7425 6200)(-7500 6200);
WIRE 16 -1 (-7425 6300)(-7425 6250);
WIRE 16 -1 (-7425 6250)(-7500 6250);
WIRE 16 -1 (-7500 6300)(-7425 6300);
WIRE 16 -1 (-7425 6300)(-7425 6350);
WIRE 16 -1 (-7425 6550)(-7425 6350);
WIRE 16 -1 (-7500 6350)(-7425 6350);
WIRE 16 -1 (-8875 600)(-8800 600);
WIRE 16 -1 (-8875 650)(-8875 600);
WIRE 16 -1 (-8875 650)(-8800 650);
WIRE 16 -1 (-8875 700)(-8875 650);
WIRE 16 -1 (-8875 700)(-8800 700);
WIRE 16 -1 (-8875 750)(-8875 700);
WIRE 16 -1 (-8875 800)(-8875 750);
WIRE 16 -1 (-8875 750)(-8800 750);
WIRE 16 -1 (-8875 800)(-8800 800);
WIRE 16 -1 (-8875 850)(-8875 800);
WIRE 16 -1 (-8875 850)(-8800 850);
WIRE 16 -1 (-8875 900)(-8875 850);
WIRE 16 -1 (-8875 900)(-8800 900);
WIRE 16 -1 (-8875 950)(-8875 900);
WIRE 16 -1 (-8875 950)(-8800 950);
WIRE 16 -1 (-8875 1000)(-8875 950);
WIRE 16 -1 (-8875 1050)(-8875 1000);
WIRE 16 -1 (-8875 1000)(-8800 1000);
WIRE 16 -1 (-8875 1050)(-8800 1050);
WIRE 16 -1 (-8875 1100)(-8875 1050);
WIRE 16 -1 (-8875 1100)(-8800 1100);
WIRE 16 -1 (-8875 1150)(-8875 1100);
WIRE 16 -1 (-8875 1150)(-8800 1150);
WIRE 16 -1 (-8875 1200)(-8875 1150);
WIRE 16 -1 (-8875 1200)(-8800 1200);
WIRE 16 -1 (-8875 1250)(-8875 1200);
WIRE 16 -1 (-8875 1300)(-8875 1250);
WIRE 16 -1 (-8875 1250)(-8800 1250);
WIRE 16 -1 (-8875 1300)(-8800 1300);
WIRE 16 -1 (-8875 1350)(-8875 1300);
WIRE 16 -1 (-8875 1350)(-8800 1350);
WIRE 16 -1 (-8875 1400)(-8875 1350);
WIRE 16 -1 (-8875 1400)(-8800 1400);
WIRE 16 -1 (-8875 1450)(-8875 1400);
WIRE 16 -1 (-8875 1450)(-8800 1450);
WIRE 16 -1 (-8875 1500)(-8875 1450);
WIRE 16 -1 (-8875 1550)(-8875 1500);
WIRE 16 -1 (-8875 1500)(-8800 1500);
WIRE 16 -1 (-8875 1550)(-8800 1550);
WIRE 16 -1 (-8875 1600)(-8875 1550);
WIRE 16 -1 (-8875 1600)(-8800 1600);
WIRE 16 -1 (-8875 1650)(-8875 1600);
WIRE 16 -1 (-8875 1650)(-8800 1650);
WIRE 16 -1 (-8875 1700)(-8875 1650);
WIRE 16 -1 (-8875 1700)(-8800 1700);
WIRE 16 -1 (-8875 1750)(-8875 1700);
WIRE 16 -1 (-8875 1800)(-8875 1750);
WIRE 16 -1 (-8875 1750)(-8800 1750);
WIRE 16 -1 (-8875 1800)(-8800 1800);
WIRE 16 -1 (-8875 1850)(-8875 1800);
WIRE 16 -1 (-8875 1850)(-8800 1850);
WIRE 16 -1 (-8875 1900)(-8875 1850);
WIRE 16 -1 (-8875 1900)(-8800 1900);
WIRE 16 -1 (-8875 1950)(-8875 1900);
WIRE 16 -1 (-8875 1950)(-8800 1950);
WIRE 16 -1 (-8875 2000)(-8875 1950);
WIRE 16 -1 (-8875 2050)(-8875 2000);
WIRE 16 -1 (-8875 2000)(-8800 2000);
WIRE 16 -1 (-8875 2050)(-8800 2050);
WIRE 16 -1 (-8875 2100)(-8875 2050);
WIRE 16 -1 (-8875 2100)(-8800 2100);
WIRE 16 -1 (-8875 2150)(-8875 2100);
WIRE 16 -1 (-8875 2150)(-8800 2150);
WIRE 16 -1 (-8875 2200)(-8875 2150);
WIRE 16 -1 (-8875 2200)(-8800 2200);
WIRE 16 -1 (-8875 2250)(-8875 2200);
WIRE 16 -1 (-8875 2250)(-8800 2250);
WIRE 16 -1 (-8875 2300)(-8875 2250);
WIRE 16 -1 (-8875 2350)(-8875 2300);
WIRE 16 -1 (-8875 2300)(-8800 2300);
WIRE 16 -1 (-8875 2350)(-8800 2350);
WIRE 16 -1 (-8875 2400)(-8875 2350);
WIRE 16 -1 (-8875 2400)(-8800 2400);
WIRE 16 -1 (-8875 2450)(-8875 2400);
WIRE 16 -1 (-8875 2450)(-8800 2450);
WIRE 16 -1 (-8875 2500)(-8875 2450);
WIRE 16 -1 (-8875 2500)(-8800 2500);
WIRE 16 -1 (-8875 2550)(-8875 2500);
WIRE 16 -1 (-8875 2600)(-8875 2550);
WIRE 16 -1 (-8875 2550)(-8800 2550);
WIRE 16 -1 (-8875 2600)(-8800 2600);
WIRE 16 -1 (-8875 2650)(-8875 2600);
WIRE 16 -1 (-8875 2650)(-8800 2650);
WIRE 16 -1 (-8875 2700)(-8875 2650);
WIRE 16 -1 (-8875 2700)(-8800 2700);
WIRE 16 -1 (-8875 2750)(-8875 2700);
WIRE 16 -1 (-8875 2750)(-8800 2750);
WIRE 16 -1 (-8875 2800)(-8875 2750);
WIRE 16 -1 (-8875 2850)(-8875 2800);
WIRE 16 -1 (-8875 2800)(-8800 2800);
WIRE 16 -1 (-8875 2850)(-8800 2850);
WIRE 16 -1 (-8875 2900)(-8875 2850);
WIRE 16 -1 (-8875 2900)(-8800 2900);
WIRE 16 -1 (-8875 2950)(-8875 2900);
WIRE 16 -1 (-8875 2950)(-8800 2950);
WIRE 16 -1 (-8875 3000)(-8875 2950);
WIRE 16 -1 (-8875 3000)(-8800 3000);
WIRE 16 -1 (-8875 3050)(-8875 3000);
WIRE 16 -1 (-8875 3100)(-8875 3050);
WIRE 16 -1 (-8875 3050)(-8800 3050);
WIRE 16 -1 (-8875 3100)(-8800 3100);
WIRE 16 -1 (-8875 3150)(-8875 3100);
WIRE 16 -1 (-8875 3150)(-8800 3150);
WIRE 16 -1 (-8875 3200)(-8875 3150);
WIRE 16 -1 (-8875 3200)(-8800 3200);
WIRE 16 -1 (-8875 3250)(-8875 3200);
WIRE 16 -1 (-8875 3250)(-8800 3250);
WIRE 16 -1 (-8875 3300)(-8875 3250);
WIRE 16 -1 (-8875 3350)(-8875 3300);
WIRE 16 -1 (-8875 3300)(-8800 3300);
WIRE 16 -1 (-8875 3350)(-8800 3350);
WIRE 16 -1 (-8875 3400)(-8875 3350);
WIRE 16 -1 (-8875 3400)(-8800 3400);
WIRE 16 -1 (-8875 3450)(-8875 3400);
WIRE 16 -1 (-8875 3450)(-8800 3450);
WIRE 16 -1 (-8875 3500)(-8875 3450);
WIRE 16 -1 (-8875 3500)(-8800 3500);
WIRE 16 -1 (-8875 3550)(-8875 3500);
WIRE 16 -1 (-8875 3600)(-8875 3550);
WIRE 16 -1 (-8875 3550)(-8800 3550);
WIRE 16 -1 (-8875 3600)(-8800 3600);
WIRE 16 -1 (-8875 3650)(-8875 3600);
WIRE 16 -1 (-8875 3650)(-8800 3650);
WIRE 16 -1 (-8875 3700)(-8875 3650);
WIRE 16 -1 (-8875 3700)(-8800 3700);
WIRE 16 -1 (-8875 3750)(-8875 3700);
WIRE 16 -1 (-8875 3750)(-8800 3750);
WIRE 16 -1 (-8875 3800)(-8875 3750);
WIRE 16 -1 (-8875 3850)(-8875 3800);
WIRE 16 -1 (-8875 3800)(-8800 3800);
WIRE 16 -1 (-8875 3850)(-8800 3850);
WIRE 16 -1 (-8875 3900)(-8875 3850);
WIRE 16 -1 (-8875 3900)(-8800 3900);
WIRE 16 -1 (-8875 3950)(-8875 3900);
WIRE 16 -1 (-8875 3950)(-8800 3950);
WIRE 16 -1 (-8875 4000)(-8875 3950);
WIRE 16 -1 (-8875 4000)(-8800 4000);
WIRE 16 -1 (-8875 4050)(-8875 4000);
WIRE 16 -1 (-8875 4100)(-8875 4050);
WIRE 16 -1 (-8875 4050)(-8800 4050);
WIRE 16 -1 (-8875 4100)(-8800 4100);
WIRE 16 -1 (-8875 4150)(-8875 4100);
WIRE 16 -1 (-8875 4150)(-8800 4150);
WIRE 16 -1 (-8875 4200)(-8875 4150);
WIRE 16 -1 (-8875 4200)(-8800 4200);
WIRE 16 -1 (-8875 4250)(-8875 4200);
WIRE 16 -1 (-8875 4250)(-8800 4250);
WIRE 16 -1 (-8875 4300)(-8875 4250);
WIRE 16 -1 (-8875 4300)(-8800 4300);
WIRE 16 -1 (-8875 4350)(-8875 4300);
WIRE 16 -1 (-8875 4400)(-8875 4350);
WIRE 16 -1 (-8875 4350)(-8800 4350);
WIRE 16 -1 (-8875 4400)(-8800 4400);
WIRE 16 -1 (-8875 4450)(-8875 4400);
WIRE 16 -1 (-8875 4450)(-8800 4450);
WIRE 16 -1 (-8875 4500)(-8875 4450);
WIRE 16 -1 (-8875 4500)(-8800 4500);
WIRE 16 -1 (-8875 4550)(-8875 4500);
WIRE 16 -1 (-8875 4550)(-8800 4550);
WIRE 16 -1 (-8875 4600)(-8875 4550);
WIRE 16 -1 (-8875 4650)(-8875 4600);
WIRE 16 -1 (-8875 4600)(-8800 4600);
WIRE 16 -1 (-8875 4650)(-8800 4650);
WIRE 16 -1 (-8875 4700)(-8875 4650);
WIRE 16 -1 (-8875 4700)(-8800 4700);
WIRE 16 -1 (-8875 4750)(-8875 4700);
WIRE 16 -1 (-8875 4750)(-8800 4750);
WIRE 16 -1 (-8875 4800)(-8875 4750);
WIRE 16 -1 (-8875 4800)(-8800 4800);
WIRE 16 -1 (-8875 4850)(-8875 4800);
WIRE 16 -1 (-8875 4900)(-8875 4850);
WIRE 16 -1 (-8875 4850)(-8800 4850);
WIRE 16 -1 (-8875 4900)(-8800 4900);
WIRE 16 -1 (-8875 4950)(-8875 4900);
WIRE 16 -1 (-8875 4950)(-8800 4950);
WIRE 16 -1 (-8875 5000)(-8875 4950);
WIRE 16 -1 (-8875 5000)(-8800 5000);
WIRE 16 -1 (-8875 5050)(-8875 5000);
WIRE 16 -1 (-8875 5050)(-8800 5050);
WIRE 16 -1 (-8875 5100)(-8875 5050);
WIRE 16 -1 (-8875 5150)(-8875 5100);
WIRE 16 -1 (-8875 5100)(-8800 5100);
WIRE 16 -1 (-8875 5150)(-8800 5150);
WIRE 16 -1 (-8875 5200)(-8875 5150);
WIRE 16 -1 (-8875 5200)(-8800 5200);
WIRE 16 -1 (-8875 5250)(-8875 5200);
WIRE 16 -1 (-8875 5250)(-8800 5250);
WIRE 16 -1 (-8875 5300)(-8875 5250);
WIRE 16 -1 (-8875 5300)(-8800 5300);
WIRE 16 -1 (-8875 5350)(-8875 5300);
WIRE 16 -1 (-8875 5400)(-8875 5350);
WIRE 16 -1 (-8875 5350)(-8800 5350);
WIRE 16 -1 (-8875 5400)(-8800 5400);
WIRE 16 -1 (-8875 5450)(-8875 5400);
WIRE 16 -1 (-8875 5450)(-8800 5450);
WIRE 16 -1 (-8875 5500)(-8875 5450);
WIRE 16 -1 (-8875 5500)(-8800 5500);
WIRE 16 -1 (-8875 5550)(-8875 5500);
WIRE 16 -1 (-8875 5550)(-8800 5550);
WIRE 16 -1 (-8875 5600)(-8875 5550);
WIRE 16 -1 (-8875 5650)(-8875 5600);
WIRE 16 -1 (-8875 5600)(-8800 5600);
WIRE 16 -1 (-8875 5650)(-8800 5650);
WIRE 16 -1 (-8875 5700)(-8875 5650);
WIRE 16 -1 (-8875 5700)(-8800 5700);
WIRE 16 -1 (-8875 5750)(-8875 5700);
WIRE 16 -1 (-8875 5750)(-8800 5750);
WIRE 16 -1 (-8875 5800)(-8875 5750);
WIRE 16 -1 (-8875 5800)(-8800 5800);
WIRE 16 -1 (-8875 5850)(-8875 5800);
WIRE 16 -1 (-8875 5900)(-8875 5850);
WIRE 16 -1 (-8875 5850)(-8800 5850);
WIRE 16 -1 (-8875 5900)(-8800 5900);
WIRE 16 -1 (-8875 5950)(-8875 5900);
WIRE 16 -1 (-8875 5950)(-8800 5950);
WIRE 16 -1 (-8875 6000)(-8875 5950);
WIRE 16 -1 (-8875 6000)(-8800 6000);
WIRE 16 -1 (-8875 6050)(-8875 6000);
WIRE 16 -1 (-8875 6050)(-8800 6050);
WIRE 16 -1 (-8875 6100)(-8875 6050);
WIRE 16 -1 (-8875 6150)(-8875 6100);
WIRE 16 -1 (-8875 6100)(-8800 6100);
WIRE 16 -1 (-8875 6150)(-8800 6150);
WIRE 16 -1 (-8875 6200)(-8875 6150);
WIRE 16 -1 (-8875 6200)(-8800 6200);
WIRE 16 -1 (-8875 6250)(-8875 6200);
WIRE 16 -1 (-8875 6250)(-8800 6250);
WIRE 16 -1 (-8875 6300)(-8875 6250);
WIRE 16 -1 (-8875 6300)(-8800 6300);
WIRE 16 -1 (-8875 6350)(-8875 6300);
WIRE 16 -1 (-8875 6550)(-8875 6350);
WIRE 16 -1 (-8875 6350)(-8800 6350);
WIRE 16 -1 (-5575 275)(-5525 275);
WIRE 16 -1 (-5525 325)(-5525 275);
WIRE 16 -1 (-5525 325)(-5525 375);
WIRE 16 -1 (-5575 325)(-5525 325);
WIRE 16 -1 (-5525 425)(-5525 375);
WIRE 16 -1 (-5575 375)(-5525 375);
WIRE 16 -1 (-5525 425)(-5525 475);
WIRE 16 -1 (-5575 425)(-5525 425);
WIRE 16 -1 (-5525 475)(-5525 525);
WIRE 16 -1 (-5575 475)(-5525 475);
WIRE 16 -1 (-5525 525)(-5525 575);
WIRE 16 -1 (-5575 525)(-5525 525);
WIRE 16 -1 (-5525 575)(-5525 625);
WIRE 16 -1 (-5575 575)(-5525 575);
WIRE 16 -1 (-5525 625)(-5525 675);
WIRE 16 -1 (-5575 625)(-5525 625);
WIRE 16 -1 (-5525 675)(-5525 725);
WIRE 16 -1 (-5575 675)(-5525 675);
WIRE 16 -1 (-5525 725)(-5525 775);
WIRE 16 -1 (-5575 725)(-5525 725);
WIRE 16 -1 (-5525 775)(-5525 825);
WIRE 16 -1 (-5575 775)(-5525 775);
WIRE 16 -1 (-5525 825)(-5525 875);
WIRE 16 -1 (-5575 825)(-5525 825);
WIRE 16 -1 (-5525 875)(-5525 925);
WIRE 16 -1 (-5575 875)(-5525 875);
WIRE 16 -1 (-5525 925)(-5525 975);
WIRE 16 -1 (-5575 925)(-5525 925);
WIRE 16 -1 (-5525 975)(-5525 1025);
WIRE 16 -1 (-5575 975)(-5525 975);
WIRE 16 -1 (-5525 1025)(-5525 1075);
WIRE 16 -1 (-5575 1025)(-5525 1025);
WIRE 16 -1 (-5525 1075)(-5525 1125);
WIRE 16 -1 (-5575 1075)(-5525 1075);
WIRE 16 -1 (-5525 1125)(-5525 1175);
WIRE 16 -1 (-5575 1125)(-5525 1125);
WIRE 16 -1 (-5525 1175)(-5525 1225);
WIRE 16 -1 (-5575 1175)(-5525 1175);
WIRE 16 -1 (-5525 1225)(-5525 1275);
WIRE 16 -1 (-5575 1225)(-5525 1225);
WIRE 16 -1 (-5525 1275)(-5525 1325);
WIRE 16 -1 (-5575 1275)(-5525 1275);
WIRE 16 -1 (-5525 1325)(-5525 1375);
WIRE 16 -1 (-5575 1325)(-5525 1325);
WIRE 16 -1 (-5525 1375)(-5525 1425);
WIRE 16 -1 (-5575 1375)(-5525 1375);
WIRE 16 -1 (-5525 1425)(-5525 1475);
WIRE 16 -1 (-5575 1425)(-5525 1425);
WIRE 16 -1 (-5525 1475)(-5525 1525);
WIRE 16 -1 (-5575 1475)(-5525 1475);
WIRE 16 -1 (-5525 1525)(-5525 1575);
WIRE 16 -1 (-5575 1525)(-5525 1525);
WIRE 16 -1 (-5525 1575)(-5525 1625);
WIRE 16 -1 (-5575 1575)(-5525 1575);
WIRE 16 -1 (-5525 1625)(-5525 1675);
WIRE 16 -1 (-5575 1625)(-5525 1625);
WIRE 16 -1 (-5525 1675)(-5525 1725);
WIRE 16 -1 (-5575 1675)(-5525 1675);
WIRE 16 -1 (-5525 1725)(-5525 1775);
WIRE 16 -1 (-5575 1725)(-5525 1725);
WIRE 16 -1 (-5525 1775)(-5525 1825);
WIRE 16 -1 (-5575 1775)(-5525 1775);
WIRE 16 -1 (-5525 1825)(-5525 1875);
WIRE 16 -1 (-5575 1825)(-5525 1825);
WIRE 16 -1 (-5525 1875)(-5525 1925);
WIRE 16 -1 (-5575 1875)(-5525 1875);
WIRE 16 -1 (-5525 1925)(-5525 1975);
WIRE 16 -1 (-5575 1925)(-5525 1925);
WIRE 16 -1 (-5525 1975)(-5525 2025);
WIRE 16 -1 (-5575 1975)(-5525 1975);
WIRE 16 -1 (-5525 2025)(-5525 2075);
WIRE 16 -1 (-5575 2025)(-5525 2025);
WIRE 16 -1 (-5525 2075)(-5525 2125);
WIRE 16 -1 (-5575 2075)(-5525 2075);
WIRE 16 -1 (-5525 2125)(-5525 2175);
WIRE 16 -1 (-5575 2125)(-5525 2125);
WIRE 16 -1 (-5525 2175)(-5525 2225);
WIRE 16 -1 (-5575 2175)(-5525 2175);
WIRE 16 -1 (-5525 2225)(-5525 2275);
WIRE 16 -1 (-5575 2225)(-5525 2225);
WIRE 16 -1 (-5525 2275)(-5525 2325);
WIRE 16 -1 (-5575 2275)(-5525 2275);
WIRE 16 -1 (-5525 2325)(-5525 2375);
WIRE 16 -1 (-5575 2325)(-5525 2325);
WIRE 16 -1 (-5525 2375)(-5525 2425);
WIRE 16 -1 (-5575 2375)(-5525 2375);
WIRE 16 -1 (-5525 2425)(-5525 2475);
WIRE 16 -1 (-5575 2425)(-5525 2425);
WIRE 16 -1 (-5525 2475)(-5525 2525);
WIRE 16 -1 (-5575 2475)(-5525 2475);
WIRE 16 -1 (-5525 2525)(-5525 2575);
WIRE 16 -1 (-5575 2525)(-5525 2525);
WIRE 16 -1 (-5525 2575)(-5525 2625);
WIRE 16 -1 (-5575 2575)(-5525 2575);
WIRE 16 -1 (-5525 2625)(-5525 2675);
WIRE 16 -1 (-5575 2625)(-5525 2625);
WIRE 16 -1 (-5525 2675)(-5525 2725);
WIRE 16 -1 (-5575 2675)(-5525 2675);
WIRE 16 -1 (-5525 2725)(-5525 2775);
WIRE 16 -1 (-5575 2725)(-5525 2725);
WIRE 16 -1 (-5525 2775)(-5525 2825);
WIRE 16 -1 (-5575 2775)(-5525 2775);
WIRE 16 -1 (-5525 2825)(-5525 2875);
WIRE 16 -1 (-5575 2825)(-5525 2825);
WIRE 16 -1 (-5525 2875)(-5525 2925);
WIRE 16 -1 (-5575 2875)(-5525 2875);
WIRE 16 -1 (-5525 2925)(-5525 2975);
WIRE 16 -1 (-5575 2925)(-5525 2925);
WIRE 16 -1 (-5525 2975)(-5525 3025);
WIRE 16 -1 (-5575 2975)(-5525 2975);
WIRE 16 -1 (-5525 3025)(-5525 3075);
WIRE 16 -1 (-5575 3025)(-5525 3025);
WIRE 16 -1 (-5525 3075)(-5525 3125);
WIRE 16 -1 (-5575 3075)(-5525 3075);
WIRE 16 -1 (-5525 3125)(-5525 3175);
WIRE 16 -1 (-5575 3125)(-5525 3125);
WIRE 16 -1 (-5525 3175)(-5525 3225);
WIRE 16 -1 (-5575 3175)(-5525 3175);
WIRE 16 -1 (-5525 3225)(-5525 3275);
WIRE 16 -1 (-5575 3225)(-5525 3225);
WIRE 16 -1 (-5525 3275)(-5525 3325);
WIRE 16 -1 (-5575 3275)(-5525 3275);
WIRE 16 -1 (-5525 3325)(-5525 3375);
WIRE 16 -1 (-5575 3325)(-5525 3325);
WIRE 16 -1 (-5525 3375)(-5525 3425);
WIRE 16 -1 (-5575 3375)(-5525 3375);
WIRE 16 -1 (-5525 3425)(-5525 3475);
WIRE 16 -1 (-5575 3425)(-5525 3425);
WIRE 16 -1 (-5525 3475)(-5525 3525);
WIRE 16 -1 (-5575 3475)(-5525 3475);
WIRE 16 -1 (-5525 3525)(-5525 3575);
WIRE 16 -1 (-5575 3525)(-5525 3525);
WIRE 16 -1 (-5525 3575)(-5525 3625);
WIRE 16 -1 (-5575 3575)(-5525 3575);
WIRE 16 -1 (-5525 3625)(-5525 3675);
WIRE 16 -1 (-5575 3625)(-5525 3625);
WIRE 16 -1 (-5525 3675)(-5525 3725);
WIRE 16 -1 (-5575 3675)(-5525 3675);
WIRE 16 -1 (-5525 3725)(-5525 3775);
WIRE 16 -1 (-5575 3725)(-5525 3725);
WIRE 16 -1 (-5525 3775)(-5525 3825);
WIRE 16 -1 (-5575 3775)(-5525 3775);
WIRE 16 -1 (-5525 3825)(-5525 3875);
WIRE 16 -1 (-5575 3825)(-5525 3825);
WIRE 16 -1 (-5525 3875)(-5525 3925);
WIRE 16 -1 (-5575 3875)(-5525 3875);
WIRE 16 -1 (-5525 3925)(-5525 3975);
WIRE 16 -1 (-5575 3925)(-5525 3925);
WIRE 16 -1 (-5525 3975)(-5525 4025);
WIRE 16 -1 (-5575 3975)(-5525 3975);
WIRE 16 -1 (-5525 4025)(-5525 4075);
WIRE 16 -1 (-5575 4025)(-5525 4025);
WIRE 16 -1 (-5525 4075)(-5525 4125);
WIRE 16 -1 (-5575 4075)(-5525 4075);
WIRE 16 -1 (-5525 4125)(-5525 4175);
WIRE 16 -1 (-5575 4125)(-5525 4125);
WIRE 16 -1 (-5525 4175)(-5525 4225);
WIRE 16 -1 (-5575 4175)(-5525 4175);
WIRE 16 -1 (-5525 4225)(-5525 4275);
WIRE 16 -1 (-5575 4225)(-5525 4225);
WIRE 16 -1 (-5525 4275)(-5525 4325);
WIRE 16 -1 (-5575 4275)(-5525 4275);
WIRE 16 -1 (-5525 4325)(-5525 4375);
WIRE 16 -1 (-5575 4325)(-5525 4325);
WIRE 16 -1 (-5525 4375)(-5525 4425);
WIRE 16 -1 (-5575 4375)(-5525 4375);
WIRE 16 -1 (-5525 4425)(-5525 4475);
WIRE 16 -1 (-5575 4425)(-5525 4425);
WIRE 16 -1 (-5525 4475)(-5525 4525);
WIRE 16 -1 (-5575 4475)(-5525 4475);
WIRE 16 -1 (-5525 4525)(-5525 4575);
WIRE 16 -1 (-5575 4525)(-5525 4525);
WIRE 16 -1 (-5525 4575)(-5525 4625);
WIRE 16 -1 (-5575 4575)(-5525 4575);
WIRE 16 -1 (-5525 4625)(-5525 4675);
WIRE 16 -1 (-5575 4625)(-5525 4625);
WIRE 16 -1 (-5525 4675)(-5525 4725);
WIRE 16 -1 (-5575 4675)(-5525 4675);
WIRE 16 -1 (-5525 4725)(-5525 4775);
WIRE 16 -1 (-5575 4725)(-5525 4725);
WIRE 16 -1 (-5525 4775)(-5525 4825);
WIRE 16 -1 (-5575 4775)(-5525 4775);
WIRE 16 -1 (-5525 4825)(-5525 4875);
WIRE 16 -1 (-5575 4825)(-5525 4825);
WIRE 16 -1 (-5525 4875)(-5525 4925);
WIRE 16 -1 (-5575 4875)(-5525 4875);
WIRE 16 -1 (-5525 4925)(-5525 4975);
WIRE 16 -1 (-5575 4925)(-5525 4925);
WIRE 16 -1 (-5525 4975)(-5525 5025);
WIRE 16 -1 (-5575 4975)(-5525 4975);
WIRE 16 -1 (-5525 5025)(-5525 5075);
WIRE 16 -1 (-5575 5025)(-5525 5025);
WIRE 16 -1 (-5525 5075)(-5525 5125);
WIRE 16 -1 (-5575 5075)(-5525 5075);
WIRE 16 -1 (-5525 5125)(-5525 5175);
WIRE 16 -1 (-5575 5125)(-5525 5125);
WIRE 16 -1 (-5525 5175)(-5525 5225);
WIRE 16 -1 (-5575 5175)(-5525 5175);
WIRE 16 -1 (-5525 5225)(-5525 5275);
WIRE 16 -1 (-5575 5225)(-5525 5225);
WIRE 16 -1 (-5525 5275)(-5525 5325);
WIRE 16 -1 (-5575 5275)(-5525 5275);
WIRE 16 -1 (-5525 5325)(-5525 5375);
WIRE 16 -1 (-5575 5325)(-5525 5325);
WIRE 16 -1 (-5525 5375)(-5525 5425);
WIRE 16 -1 (-5575 5375)(-5525 5375);
WIRE 16 -1 (-5525 5425)(-5525 5475);
WIRE 16 -1 (-5575 5425)(-5525 5425);
WIRE 16 -1 (-5525 5475)(-5525 5525);
WIRE 16 -1 (-5575 5475)(-5525 5475);
WIRE 16 -1 (-5525 5525)(-5525 5575);
WIRE 16 -1 (-5575 5525)(-5525 5525);
WIRE 16 -1 (-5525 5575)(-5525 5625);
WIRE 16 -1 (-5575 5575)(-5525 5575);
WIRE 16 -1 (-5525 5625)(-5525 5675);
WIRE 16 -1 (-5575 5625)(-5525 5625);
WIRE 16 -1 (-5525 5675)(-5525 5725);
WIRE 16 -1 (-5575 5675)(-5525 5675);
WIRE 16 -1 (-5525 5725)(-5525 5775);
WIRE 16 -1 (-5575 5725)(-5525 5725);
WIRE 16 -1 (-5525 5775)(-5525 5825);
WIRE 16 -1 (-5575 5775)(-5525 5775);
WIRE 16 -1 (-5525 5825)(-5525 5875);
WIRE 16 -1 (-5575 5825)(-5525 5825);
WIRE 16 -1 (-5525 5875)(-5525 5925);
WIRE 16 -1 (-5575 5875)(-5525 5875);
WIRE 16 -1 (-5525 5925)(-5525 5975);
WIRE 16 -1 (-5575 5925)(-5525 5925);
WIRE 16 -1 (-5525 5975)(-5525 6025);
WIRE 16 -1 (-5575 5975)(-5525 5975);
WIRE 16 -1 (-5525 6025)(-5525 6075);
WIRE 16 -1 (-5575 6025)(-5525 6025);
WIRE 16 -1 (-5525 6075)(-5525 6125);
WIRE 16 -1 (-5575 6075)(-5525 6075);
WIRE 16 -1 (-5525 6125)(-5525 6175);
WIRE 16 -1 (-5575 6125)(-5525 6125);
WIRE 16 -1 (-5525 6175)(-5525 6225);
WIRE 16 -1 (-5575 6175)(-5525 6175);
WIRE 16 -1 (-5525 6225)(-5525 6275);
WIRE 16 -1 (-5575 6225)(-5525 6225);
WIRE 16 -1 (-5525 6275)(-5525 6325);
WIRE 16 -1 (-5575 6275)(-5525 6275);
WIRE 16 -1 (-5525 6325)(-5525 6375);
WIRE 16 -1 (-5575 6325)(-5525 6325);
WIRE 16 -1 (-5525 6375)(-5525 6425);
WIRE 16 -1 (-5575 6375)(-5525 6375);
WIRE 16 -1 (-5575 6425)(-5525 6425);
WIRE 16 -1 (-5525 6500)(-5525 6425);
WIRE 16 -1 (-6950 725)(-6875 725);
WIRE 16 -1 (-6950 775)(-6950 725);
WIRE 16 -1 (-6950 775)(-6875 775);
WIRE 16 -1 (-6950 775)(-6950 825);
WIRE 16 -1 (-6950 825)(-6875 825);
WIRE 16 -1 (-6950 825)(-6950 875);
WIRE 16 -1 (-6950 875)(-6875 875);
WIRE 16 -1 (-6950 875)(-6950 925);
WIRE 16 -1 (-6950 925)(-6875 925);
WIRE 16 -1 (-6950 925)(-6950 975);
WIRE 16 -1 (-6950 975)(-6950 1025);
WIRE 16 -1 (-6950 975)(-6875 975);
WIRE 16 -1 (-6950 1025)(-6875 1025);
WIRE 16 -1 (-6950 1025)(-6950 1075);
WIRE 16 -1 (-6950 1075)(-6875 1075);
WIRE 16 -1 (-6950 1075)(-6950 1125);
WIRE 16 -1 (-6950 1125)(-6875 1125);
WIRE 16 -1 (-6950 1125)(-6950 1175);
WIRE 16 -1 (-6875 1175)(-6950 1175);
WIRE 16 -1 (-6950 1175)(-6950 1225);
WIRE 16 -1 (-6950 1225)(-6875 1225);
WIRE 16 -1 (-6950 1225)(-6950 1275);
WIRE 16 -1 (-6950 1275)(-6875 1275);
WIRE 16 -1 (-6950 1275)(-6950 1325);
WIRE 16 -1 (-6950 1325)(-6875 1325);
WIRE 16 -1 (-6950 1325)(-6950 1375);
WIRE 16 -1 (-6950 1375)(-6875 1375);
WIRE 16 -1 (-6950 1375)(-6950 1425);
WIRE 16 -1 (-6950 1425)(-6875 1425);
WIRE 16 -1 (-6950 1425)(-6950 1475);
WIRE 16 -1 (-6950 1475)(-6875 1475);
WIRE 16 -1 (-6950 1475)(-6950 1525);
WIRE 16 -1 (-6950 1525)(-6950 1575);
WIRE 16 -1 (-6950 1525)(-6875 1525);
WIRE 16 -1 (-6950 1575)(-6875 1575);
WIRE 16 -1 (-6950 1575)(-6950 1625);
WIRE 16 -1 (-6950 1625)(-6875 1625);
WIRE 16 -1 (-6950 1625)(-6950 1675);
WIRE 16 -1 (-6950 1675)(-6875 1675);
WIRE 16 -1 (-6950 1675)(-6950 1725);
WIRE 16 -1 (-6950 1725)(-6875 1725);
WIRE 16 -1 (-6950 1725)(-6950 1775);
WIRE 16 -1 (-6950 1775)(-6875 1775);
WIRE 16 -1 (-6950 1775)(-6950 1825);
WIRE 16 -1 (-6950 1825)(-6875 1825);
WIRE 16 -1 (-6950 1825)(-6950 1875);
WIRE 16 -1 (-6875 1875)(-6950 1875);
WIRE 16 -1 (-6950 1875)(-6950 1925);
WIRE 16 -1 (-6950 1925)(-6875 1925);
WIRE 16 -1 (-6950 1925)(-6950 1975);
WIRE 16 -1 (-6950 1975)(-6875 1975);
WIRE 16 -1 (-6950 1975)(-6950 2025);
WIRE 16 -1 (-6950 2025)(-6950 2075);
WIRE 16 -1 (-6950 2025)(-6875 2025);
WIRE 16 -1 (-6950 2075)(-6875 2075);
WIRE 16 -1 (-6950 2075)(-6950 2125);
WIRE 16 -1 (-6950 2125)(-6875 2125);
WIRE 16 -1 (-6950 2125)(-6950 2175);
WIRE 16 -1 (-6950 2175)(-6875 2175);
WIRE 16 -1 (-6950 2175)(-6950 2225);
WIRE 16 -1 (-6950 2225)(-6875 2225);
WIRE 16 -1 (-6950 2225)(-6950 2275);
WIRE 16 -1 (-6950 2275)(-6875 2275);
WIRE 16 -1 (-6950 2275)(-6950 2325);
WIRE 16 -1 (-6950 2325)(-6875 2325);
WIRE 16 -1 (-6950 2325)(-6950 2375);
WIRE 16 -1 (-6950 2375)(-6875 2375);
WIRE 16 -1 (-6950 2375)(-6950 2425);
WIRE 16 -1 (-6950 2425)(-6875 2425);
WIRE 16 -1 (-6950 2425)(-6950 2475);
WIRE 16 -1 (-6950 2475)(-6875 2475);
WIRE 16 -1 (-6950 2475)(-6950 2525);
WIRE 16 -1 (-6950 2525)(-6950 2575);
WIRE 16 -1 (-6950 2525)(-6875 2525);
WIRE 16 -1 (-6875 2575)(-6950 2575);
WIRE 16 -1 (-6950 2575)(-6950 2625);
WIRE 16 -1 (-6950 2625)(-6875 2625);
WIRE 16 -1 (-6950 2625)(-6950 2675);
WIRE 16 -1 (-6950 2675)(-6875 2675);
WIRE 16 -1 (-6950 2675)(-6950 2725);
WIRE 16 -1 (-6950 2725)(-6875 2725);
WIRE 16 -1 (-6950 2725)(-6950 2775);
WIRE 16 -1 (-6950 2775)(-6875 2775);
WIRE 16 -1 (-6950 2775)(-6950 2825);
WIRE 16 -1 (-6950 2825)(-6875 2825);
WIRE 16 -1 (-6950 2825)(-6950 2875);
WIRE 16 -1 (-6950 2875)(-6875 2875);
WIRE 16 -1 (-6950 2875)(-6950 2925);
WIRE 16 -1 (-6950 2925)(-6875 2925);
WIRE 16 -1 (-6950 2925)(-6950 2975);
WIRE 16 -1 (-6950 2975)(-6875 2975);
WIRE 16 -1 (-6950 2975)(-6950 3025);
WIRE 16 -1 (-6950 3025)(-6950 3075);
WIRE 16 -1 (-6950 3025)(-6875 3025);
WIRE 16 -1 (-6950 3075)(-6875 3075);
WIRE 16 -1 (-6950 3075)(-6950 3125);
WIRE 16 -1 (-6950 3125)(-6875 3125);
WIRE 16 -1 (-6950 3125)(-6950 3175);
WIRE 16 -1 (-6950 3175)(-6875 3175);
WIRE 16 -1 (-6950 3175)(-6950 3225);
WIRE 16 -1 (-6950 3225)(-6875 3225);
WIRE 16 -1 (-6950 3225)(-6950 3275);
WIRE 16 -1 (-6875 3275)(-6950 3275);
WIRE 16 -1 (-6950 3275)(-6950 3325);
WIRE 16 -1 (-6950 3325)(-6875 3325);
WIRE 16 -1 (-6950 3325)(-6950 3375);
WIRE 16 -1 (-6950 3375)(-6875 3375);
WIRE 16 -1 (-6950 3375)(-6950 3425);
WIRE 16 -1 (-6950 3425)(-6875 3425);
WIRE 16 -1 (-6950 3425)(-6950 3475);
WIRE 16 -1 (-6950 3475)(-6875 3475);
WIRE 16 -1 (-6950 3475)(-6950 3525);
WIRE 16 -1 (-6950 3525)(-6875 3525);
WIRE 16 -1 (-6950 3525)(-6950 3575);
WIRE 16 -1 (-6950 3575)(-6950 3625);
WIRE 16 -1 (-6950 3575)(-6875 3575);
WIRE 16 -1 (-6950 3625)(-6875 3625);
WIRE 16 -1 (-6950 3625)(-6950 3675);
WIRE 16 -1 (-6950 3675)(-6875 3675);
WIRE 16 -1 (-6950 3675)(-6950 3725);
WIRE 16 -1 (-6950 3725)(-6875 3725);
WIRE 16 -1 (-6950 3725)(-6950 3775);
WIRE 16 -1 (-6950 3775)(-6875 3775);
WIRE 16 -1 (-6950 3775)(-6950 3825);
WIRE 16 -1 (-6950 3825)(-6875 3825);
WIRE 16 -1 (-6950 3825)(-6950 3875);
WIRE 16 -1 (-6950 3875)(-6875 3875);
WIRE 16 -1 (-6950 3875)(-6950 3925);
WIRE 16 -1 (-6950 3925)(-6875 3925);
WIRE 16 -1 (-6950 3925)(-6950 3975);
WIRE 16 -1 (-6875 3975)(-6950 3975);
WIRE 16 -1 (-6950 3975)(-6950 4025);
WIRE 16 -1 (-6950 4025)(-6875 4025);
WIRE 16 -1 (-6950 4025)(-6950 4075);
WIRE 16 -1 (-6950 4075)(-6950 4125);
WIRE 16 -1 (-6950 4075)(-6875 4075);
WIRE 16 -1 (-6950 4125)(-6875 4125);
WIRE 16 -1 (-6950 4125)(-6950 4175);
WIRE 16 -1 (-6950 4175)(-6875 4175);
WIRE 16 -1 (-6950 4175)(-6950 4225);
WIRE 16 -1 (-6950 4225)(-6875 4225);
WIRE 16 -1 (-6950 4225)(-6950 4275);
WIRE 16 -1 (-6950 4275)(-6875 4275);
WIRE 16 -1 (-6950 4275)(-6950 4325);
WIRE 16 -1 (-6950 4325)(-6875 4325);
WIRE 16 -1 (-6950 4325)(-6950 4375);
WIRE 16 -1 (-6950 4375)(-6875 4375);
WIRE 16 -1 (-6950 4375)(-6950 4425);
WIRE 16 -1 (-6950 4425)(-6875 4425);
WIRE 16 -1 (-6950 4425)(-6950 4475);
WIRE 16 -1 (-6950 4475)(-6875 4475);
WIRE 16 -1 (-6950 4475)(-6950 4525);
WIRE 16 -1 (-6950 4525)(-6875 4525);
WIRE 16 -1 (-6950 4525)(-6950 4575);
WIRE 16 -1 (-6950 4575)(-6950 4625);
WIRE 16 -1 (-6950 4575)(-6875 4575);
WIRE 16 -1 (-6950 4625)(-6875 4625);
WIRE 16 -1 (-6950 4625)(-6950 4675);
WIRE 16 -1 (-6875 4675)(-6950 4675);
WIRE 16 -1 (-6950 4675)(-6950 4725);
WIRE 16 -1 (-6950 4725)(-6875 4725);
WIRE 16 -1 (-6950 4725)(-6950 4775);
WIRE 16 -1 (-6950 4775)(-6875 4775);
WIRE 16 -1 (-6950 4775)(-6950 4825);
WIRE 16 -1 (-6950 4825)(-6875 4825);
WIRE 16 -1 (-6950 4825)(-6950 4875);
WIRE 16 -1 (-6950 4875)(-6875 4875);
WIRE 16 -1 (-6950 4875)(-6950 4925);
WIRE 16 -1 (-6950 4925)(-6875 4925);
WIRE 16 -1 (-6950 4925)(-6950 4975);
WIRE 16 -1 (-6950 4975)(-6875 4975);
WIRE 16 -1 (-6950 4975)(-6950 5025);
WIRE 16 -1 (-6950 5025)(-6875 5025);
WIRE 16 -1 (-6950 5025)(-6950 5075);
WIRE 16 -1 (-6950 5075)(-6950 5125);
WIRE 16 -1 (-6950 5075)(-6875 5075);
WIRE 16 -1 (-6950 5125)(-6875 5125);
WIRE 16 -1 (-6950 5125)(-6950 5175);
WIRE 16 -1 (-6950 5175)(-6875 5175);
WIRE 16 -1 (-6950 5175)(-6950 5225);
WIRE 16 -1 (-6950 5225)(-6875 5225);
WIRE 16 -1 (-6950 5225)(-6950 5275);
WIRE 16 -1 (-6950 5275)(-6875 5275);
WIRE 16 -1 (-6950 5275)(-6950 5325);
WIRE 16 -1 (-6950 5325)(-6875 5325);
WIRE 16 -1 (-6950 5325)(-6950 5375);
WIRE 16 -1 (-6875 5375)(-6950 5375);
WIRE 16 -1 (-6950 5375)(-6950 5425);
WIRE 16 -1 (-6950 5425)(-6875 5425);
WIRE 16 -1 (-6950 5425)(-6950 5475);
WIRE 16 -1 (-6950 5475)(-6875 5475);
WIRE 16 -1 (-6950 5475)(-6950 5525);
WIRE 16 -1 (-6950 5525)(-6875 5525);
WIRE 16 -1 (-6950 5525)(-6950 5575);
WIRE 16 -1 (-6950 5575)(-6875 5575);
WIRE 16 -1 (-6950 5575)(-6950 5625);
WIRE 16 -1 (-6950 5625)(-6950 5675);
WIRE 16 -1 (-6950 5625)(-6875 5625);
WIRE 16 -1 (-6950 5675)(-6875 5675);
WIRE 16 -1 (-6950 5675)(-6950 5725);
WIRE 16 -1 (-6950 5725)(-6875 5725);
WIRE 16 -1 (-6950 5725)(-6950 5775);
WIRE 16 -1 (-6950 5775)(-6875 5775);
WIRE 16 -1 (-6950 5775)(-6950 5825);
WIRE 16 -1 (-6950 5825)(-6875 5825);
WIRE 16 -1 (-6950 5825)(-6950 5875);
WIRE 16 -1 (-6950 5875)(-6875 5875);
WIRE 16 -1 (-6950 5875)(-6950 5925);
WIRE 16 -1 (-6950 5925)(-6875 5925);
WIRE 16 -1 (-6950 5925)(-6950 5975);
WIRE 16 -1 (-6950 5975)(-6875 5975);
WIRE 16 -1 (-6950 5975)(-6950 6025);
WIRE 16 -1 (-6950 6025)(-6875 6025);
WIRE 16 -1 (-6950 6025)(-6950 6075);
WIRE 16 -1 (-6875 6075)(-6950 6075);
WIRE 16 -1 (-6950 6075)(-6950 6125);
WIRE 16 -1 (-6950 6275)(-6950 6125);
WIRE 16 -1 (-6875 6125)(-6950 6125);
WIRE 16 -1 (-2050 825)(-2050 775);
WIRE 16 -1 (-2050 875)(-2050 825);
WIRE 16 -1 (-2050 825)(-2150 825);
WIRE 16 -1 (-2050 775)(-2150 775);
WIRE 16 -1 (-2050 925)(-2050 875);
WIRE 16 -1 (-2050 875)(-2150 875);
WIRE 16 -1 (-2050 925)(-2150 925);
WIRE 16 -1 (-2050 975)(-2050 925);
WIRE 16 -1 (-2050 1025)(-2050 975);
WIRE 16 -1 (-2150 975)(-2050 975);
WIRE 16 -1 (-2050 1075)(-2050 1025);
WIRE 16 -1 (-2050 1025)(-2150 1025);
WIRE 16 -1 (-2050 1125)(-2050 1075);
WIRE 16 -1 (-2150 1075)(-2050 1075);
WIRE 16 -1 (-2050 1175)(-2050 1125);
WIRE 16 -1 (-2050 1125)(-2150 1125);
WIRE 16 -1 (-2050 1225)(-2050 1175);
WIRE 16 -1 (-2050 1175)(-2150 1175);
WIRE 16 -1 (-2050 1275)(-2050 1225);
WIRE 16 -1 (-2150 1225)(-2050 1225);
WIRE 16 -1 (-2050 1325)(-2050 1275);
WIRE 16 -1 (-2050 1275)(-2150 1275);
WIRE 16 -1 (-2050 1325)(-2150 1325);
WIRE 16 -1 (-2050 1375)(-2050 1325);
WIRE 16 -1 (-2050 1425)(-2050 1375);
WIRE 16 -1 (-2050 1375)(-2150 1375);
WIRE 16 -1 (-2050 1475)(-2050 1425);
WIRE 16 -1 (-2050 1425)(-2150 1425);
WIRE 16 -1 (-2050 1525)(-2050 1475);
WIRE 16 -1 (-2050 1475)(-2150 1475);
WIRE 16 -1 (-2050 1575)(-2050 1525);
WIRE 16 -1 (-2150 1525)(-2050 1525);
WIRE 16 -1 (-2050 1575)(-2150 1575);
WIRE 16 -1 (-2050 1625)(-2050 1575);
WIRE 16 -1 (-2050 1675)(-2050 1625);
WIRE 16 -1 (-2050 1625)(-2150 1625);
WIRE 16 -1 (-2050 1725)(-2050 1675);
WIRE 16 -1 (-2050 1675)(-2150 1675);
WIRE 16 -1 (-2050 1775)(-2050 1725);
WIRE 16 -1 (-2050 1725)(-2150 1725);
WIRE 16 -1 (-2050 1825)(-2050 1775);
WIRE 16 -1 (-2150 1775)(-2050 1775);
WIRE 16 -1 (-2050 1825)(-2150 1825);
WIRE 16 -1 (-2050 1875)(-2050 1825);
WIRE 16 -1 (-2050 1925)(-2050 1875);
WIRE 16 -1 (-2150 1875)(-2050 1875);
WIRE 16 -1 (-2050 1975)(-2050 1925);
WIRE 16 -1 (-2050 1925)(-2150 1925);
WIRE 16 -1 (-2050 2025)(-2050 1975);
WIRE 16 -1 (-2050 1975)(-2150 1975);
WIRE 16 -1 (-2050 2075)(-2050 2025);
WIRE 16 -1 (-2150 2025)(-2050 2025);
WIRE 16 -1 (-2050 2125)(-2050 2075);
WIRE 16 -1 (-2050 2075)(-2150 2075);
WIRE 16 -1 (-2050 2175)(-2050 2125);
WIRE 16 -1 (-2050 2125)(-2150 2125);
WIRE 16 -1 (-2050 2225)(-2050 2175);
WIRE 16 -1 (-2050 2175)(-2150 2175);
WIRE 16 -1 (-2050 2225)(-2150 2225);
WIRE 16 -1 (-2050 2275)(-2050 2225);
WIRE 16 -1 (-2050 2325)(-2050 2275);
WIRE 16 -1 (-2050 2275)(-2150 2275);
WIRE 16 -1 (-2050 2375)(-2050 2325);
WIRE 16 -1 (-2150 2325)(-2050 2325);
WIRE 16 -1 (-2050 2425)(-2050 2375);
WIRE 16 -1 (-2050 2375)(-2150 2375);
WIRE 16 -1 (-2050 2475)(-2050 2425);
WIRE 16 -1 (-2050 2425)(-2150 2425);
WIRE 16 -1 (-2050 2475)(-2150 2475);
WIRE 16 -1 (-2050 2525)(-2050 2475);
WIRE 16 -1 (-2050 2575)(-2050 2525);
WIRE 16 -1 (-2050 2525)(-2150 2525);
WIRE 16 -1 (-2050 2625)(-2050 2575);
WIRE 16 -1 (-2150 2575)(-2050 2575);
WIRE 16 -1 (-2050 2675)(-2050 2625);
WIRE 16 -1 (-2050 2625)(-2150 2625);
WIRE 16 -1 (-2050 2725)(-2050 2675);
WIRE 16 -1 (-2150 2675)(-2050 2675);
WIRE 16 -1 (-2050 2725)(-2150 2725);
WIRE 16 -1 (-2050 2775)(-2050 2725);
WIRE 16 -1 (-2050 2825)(-2050 2775);
WIRE 16 -1 (-2050 2775)(-2150 2775);
WIRE 16 -1 (-2050 2875)(-2050 2825);
WIRE 16 -1 (-2150 2825)(-2050 2825);
WIRE 16 -1 (-2050 2925)(-2050 2875);
WIRE 16 -1 (-2050 2875)(-2150 2875);
WIRE 16 -1 (-2050 2975)(-2050 2925);
WIRE 16 -1 (-2050 2925)(-2150 2925);
WIRE 16 -1 (-2050 2975)(-2150 2975);
WIRE 16 -1 (-2050 3025)(-2050 2975);
WIRE 16 -1 (-2050 3075)(-2050 3025);
WIRE 16 -1 (-2050 3025)(-2150 3025);
WIRE 16 -1 (-2050 3125)(-2050 3075);
WIRE 16 -1 (-2050 3075)(-2150 3075);
WIRE 16 -1 (-2050 3175)(-2050 3125);
WIRE 16 -1 (-2150 3125)(-2050 3125);
WIRE 16 -1 (-2050 3225)(-2050 3175);
WIRE 16 -1 (-2050 3175)(-2150 3175);
WIRE 16 -1 (-2050 3275)(-2050 3225);
WIRE 16 -1 (-2050 3225)(-2150 3225);
WIRE 16 -1 (-2050 3325)(-2050 3275);
WIRE 16 -1 (-2050 3275)(-2150 3275);
WIRE 16 -1 (-2050 3375)(-2050 3325);
WIRE 16 -1 (-2050 3325)(-2150 3325);
WIRE 16 -1 (-2150 3375)(-2050 3375);
WIRE 16 -1 (-2050 3425)(-2050 3375);
WIRE 16 -1 (-2050 3475)(-2050 3425);
WIRE 16 -1 (-2050 3425)(-2150 3425);
WIRE 16 -1 (-2050 3525)(-2050 3475);
WIRE 16 -1 (-2150 3475)(-2050 3475);
WIRE 16 -1 (-2050 3575)(-2050 3525);
WIRE 16 -1 (-2050 3525)(-2150 3525);
WIRE 16 -1 (-2050 3625)(-2050 3575);
WIRE 16 -1 (-2050 3575)(-2150 3575);
WIRE 16 -1 (-2150 3625)(-2050 3625);
WIRE 16 -1 (-2050 3675)(-2050 3625);
WIRE 16 -1 (-2050 3725)(-2050 3675);
WIRE 16 -1 (-2050 3675)(-2150 3675);
WIRE 16 -1 (-2050 3775)(-2050 3725);
WIRE 16 -1 (-2050 3725)(-2150 3725);
WIRE 16 -1 (-2050 3825)(-2050 3775);
WIRE 16 -1 (-2050 3775)(-2150 3775);
WIRE 16 -1 (-2050 3875)(-2050 3825);
WIRE 16 -1 (-2050 3825)(-2150 3825);
WIRE 16 -1 (-2050 3875)(-2150 3875);
WIRE 16 -1 (-2050 3925)(-2050 3875);
WIRE 16 -1 (-2050 3975)(-2050 3925);
WIRE 16 -1 (-2150 3925)(-2050 3925);
WIRE 16 -1 (-2050 4025)(-2050 3975);
WIRE 16 -1 (-2050 3975)(-2150 3975);
WIRE 16 -1 (-2050 4075)(-2050 4025);
WIRE 16 -1 (-2050 4025)(-2150 4025);
WIRE 16 -1 (-2050 4125)(-2050 4075);
WIRE 16 -1 (-2050 4075)(-2150 4075);
WIRE 16 -1 (-2050 4125)(-2150 4125);
WIRE 16 -1 (-2050 4175)(-2050 4125);
WIRE 16 -1 (-2050 4225)(-2050 4175);
WIRE 16 -1 (-2150 4175)(-2050 4175);
WIRE 16 -1 (-2050 4275)(-2050 4225);
WIRE 16 -1 (-2050 4225)(-2150 4225);
WIRE 16 -1 (-2050 4325)(-2050 4275);
WIRE 16 -1 (-2150 4275)(-2050 4275);
WIRE 16 -1 (-2050 4375)(-2050 4325);
WIRE 16 -1 (-2050 4325)(-2150 4325);
WIRE 16 -1 (-2050 4425)(-2050 4375);
WIRE 16 -1 (-2050 4375)(-2150 4375);
WIRE 16 -1 (-2050 4475)(-2050 4425);
WIRE 16 -1 (-2150 4425)(-2050 4425);
WIRE 16 -1 (-2050 4525)(-2050 4475);
WIRE 16 -1 (-2050 4475)(-2150 4475);
WIRE 16 -1 (-2050 4525)(-2150 4525);
WIRE 16 -1 (-2050 4575)(-2050 4525);
WIRE 16 -1 (-2050 4625)(-2050 4575);
WIRE 16 -1 (-2050 4575)(-2150 4575);
WIRE 16 -1 (-2050 4675)(-2050 4625);
WIRE 16 -1 (-2050 4625)(-2150 4625);
WIRE 16 -1 (-2050 4725)(-2050 4675);
WIRE 16 -1 (-2150 4675)(-2050 4675);
WIRE 16 -1 (-2050 4775)(-2050 4725);
WIRE 16 -1 (-2050 4725)(-2150 4725);
WIRE 16 -1 (-2050 4775)(-2150 4775);
WIRE 16 -1 (-2050 4825)(-2050 4775);
WIRE 16 -1 (-2050 4875)(-2050 4825);
WIRE 16 -1 (-2050 4825)(-2150 4825);
WIRE 16 -1 (-2050 4925)(-2050 4875);
WIRE 16 -1 (-2050 4875)(-2150 4875);
WIRE 16 -1 (-2050 4975)(-2050 4925);
WIRE 16 -1 (-2150 4925)(-2050 4925);
WIRE 16 -1 (-2050 5025)(-2050 4975);
WIRE 16 -1 (-2050 4975)(-2150 4975);
WIRE 16 -1 (-2050 5025)(-2150 5025);
WIRE 16 -1 (-2050 5075)(-2050 5025);
WIRE 16 -1 (-2050 5125)(-2050 5075);
WIRE 16 -1 (-2050 5075)(-2150 5075);
WIRE 16 -1 (-2050 5175)(-2050 5125);
WIRE 16 -1 (-2050 5125)(-2150 5125);
WIRE 16 -1 (-2050 5225)(-2050 5175);
WIRE 16 -1 (-2150 5175)(-2050 5175);
WIRE 16 -1 (-2050 5275)(-2050 5225);
WIRE 16 -1 (-2050 5225)(-2150 5225);
WIRE 16 -1 (-2050 5325)(-2050 5275);
WIRE 16 -1 (-2050 5275)(-2150 5275);
WIRE 16 -1 (-2050 5375)(-2050 5325);
WIRE 16 -1 (-2050 5325)(-2150 5325);
WIRE 16 -1 (-2050 5425)(-2050 5375);
WIRE 16 -1 (-2050 5375)(-2150 5375);
WIRE 16 -1 (-2150 5425)(-2050 5425);
WIRE 16 -1 (-2050 5475)(-2050 5425);
WIRE 16 -1 (-2050 5525)(-2050 5475);
WIRE 16 -1 (-2050 5475)(-2150 5475);
WIRE 16 -1 (-2050 5575)(-2050 5525);
WIRE 16 -1 (-2050 5525)(-2150 5525);
WIRE 16 -1 (-2050 5625)(-2050 5575);
WIRE 16 -1 (-2050 5575)(-2150 5575);
WIRE 16 -1 (-2050 5675)(-2050 5625);
WIRE 16 -1 (-2050 5625)(-2150 5625);
WIRE 16 -1 (-2050 5725)(-2050 5675);
WIRE 16 -1 (-2150 5675)(-2050 5675);
WIRE 16 -1 (-2050 5775)(-2050 5725);
WIRE 16 -1 (-2050 5725)(-2150 5725);
WIRE 16 -1 (-2050 5825)(-2050 5775);
WIRE 16 -1 (-2050 5775)(-2150 5775);
WIRE 16 -1 (-2050 5875)(-2050 5825);
WIRE 16 -1 (-2050 5825)(-2150 5825);
WIRE 16 -1 (-2050 5925)(-2050 5875);
WIRE 16 -1 (-2050 5875)(-2150 5875);
WIRE 16 -1 (-2050 5975)(-2050 5925);
WIRE 16 -1 (-2150 5925)(-2050 5925);
WIRE 16 -1 (-2050 6025)(-2050 5975);
WIRE 16 -1 (-2050 5975)(-2150 5975);
WIRE 16 -1 (-2050 6075)(-2050 6025);
WIRE 16 -1 (-2050 6025)(-2150 6025);
WIRE 16 -1 (-2050 6125)(-2050 6075);
WIRE 16 -1 (-2050 6075)(-2150 6075);
WIRE 16 -1 (-2050 6175)(-2050 6125);
WIRE 16 -1 (-2050 6125)(-2150 6125);
WIRE 16 -1 (-2050 6225)(-2050 6175);
WIRE 16 -1 (-2150 6175)(-2050 6175);
WIRE 16 -1 (-2050 6275)(-2050 6225);
WIRE 16 -1 (-2050 6225)(-2150 6225);
WIRE 16 -1 (-2050 6325)(-2050 6275);
WIRE 16 -1 (-2050 6275)(-2150 6275);
WIRE 16 -1 (-2050 6375)(-2050 6325);
WIRE 16 -1 (-2050 6325)(-2150 6325);
WIRE 16 -1 (-2050 6425)(-2050 6375);
WIRE 16 -1 (-2050 6375)(-2150 6375);
WIRE 16 -1 (-2050 6475)(-2050 6425);
WIRE 16 -1 (-2150 6425)(-2050 6425);
WIRE 16 -1 (-2050 6525)(-2050 6475);
WIRE 16 -1 (-2150 6475)(-2050 6475);
WIRE 16 -1 (-3550 2675)(-3450 2675);
WIRE 16 -1 (-3550 2675)(-3550 2725);
WIRE 16 -1 (-3550 2725)(-3450 2725);
WIRE 16 -1 (-3550 2725)(-3550 2775);
WIRE 16 -1 (-3550 2775)(-3550 2825);
WIRE 16 -1 (-3550 2775)(-3450 2775);
WIRE 16 -1 (-3550 2825)(-3450 2825);
WIRE 16 -1 (-3550 2825)(-3550 2875);
WIRE 16 -1 (-3550 2875)(-3450 2875);
WIRE 16 -1 (-3550 2875)(-3550 2925);
WIRE 16 -1 (-3450 2925)(-3550 2925);
WIRE 16 -1 (-3550 2925)(-3550 2975);
WIRE 16 -1 (-3550 2975)(-3450 2975);
WIRE 16 -1 (-3550 2975)(-3550 3025);
WIRE 16 -1 (-3550 3025)(-3550 3075);
WIRE 16 -1 (-3550 3025)(-3450 3025);
WIRE 16 -1 (-3550 3075)(-3450 3075);
WIRE 16 -1 (-3550 3075)(-3550 3125);
WIRE 16 -1 (-3550 3125)(-3450 3125);
WIRE 16 -1 (-3550 3125)(-3550 3175);
WIRE 16 -1 (-3550 3175)(-3450 3175);
WIRE 16 -1 (-3550 3175)(-3550 3225);
WIRE 16 -1 (-3450 3225)(-3550 3225);
WIRE 16 -1 (-3550 3225)(-3550 3275);
WIRE 16 -1 (-3550 3275)(-3450 3275);
WIRE 16 -1 (-3550 3275)(-3550 3325);
WIRE 16 -1 (-3550 3325)(-3550 3375);
WIRE 16 -1 (-3550 3325)(-3450 3325);
WIRE 16 -1 (-3550 3375)(-3450 3375);
WIRE 16 -1 (-3550 3375)(-3550 3425);
WIRE 16 -1 (-3550 3425)(-3450 3425);
WIRE 16 -1 (-3550 3425)(-3550 3475);
WIRE 16 -1 (-3550 3475)(-3450 3475);
WIRE 16 -1 (-3550 3475)(-3550 3525);
WIRE 16 -1 (-3450 3525)(-3550 3525);
WIRE 16 -1 (-3550 3525)(-3550 3575);
WIRE 16 -1 (-3550 3575)(-3550 3625);
WIRE 16 -1 (-3550 3575)(-3450 3575);
WIRE 16 -1 (-3550 3625)(-3450 3625);
WIRE 16 -1 (-3550 3625)(-3550 3675);
WIRE 16 -1 (-3550 3675)(-3450 3675);
WIRE 16 -1 (-3550 3675)(-3550 3725);
WIRE 16 -1 (-3450 3725)(-3550 3725);
WIRE 16 -1 (-3550 3725)(-3550 3775);
WIRE 16 -1 (-3550 3775)(-3450 3775);
WIRE 16 -1 (-3550 3775)(-3550 3825);
WIRE 16 -1 (-3550 3825)(-3550 3875);
WIRE 16 -1 (-3550 3825)(-3450 3825);
WIRE 16 -1 (-3550 3875)(-3450 3875);
WIRE 16 -1 (-3550 3925)(-3550 3875);
WIRE 16 -1 (-3550 3925)(-3450 3925);
WIRE 16 -1 (-3550 3975)(-3550 3925);
WIRE 16 -1 (-3550 3975)(-3450 3975);
WIRE 16 -1 (-3550 4025)(-3550 3975);
WIRE 16 -1 (-3450 4025)(-3550 4025);
WIRE 16 -1 (-3550 4075)(-3550 4025);
WIRE 16 -1 (-3550 4125)(-3550 4075);
WIRE 16 -1 (-3550 4075)(-3450 4075);
WIRE 16 -1 (-3550 4125)(-3450 4125);
WIRE 16 -1 (-3550 4175)(-3550 4125);
WIRE 16 -1 (-3550 4175)(-3450 4175);
WIRE 16 -1 (-3550 4225)(-3550 4175);
WIRE 16 -1 (-3550 4225)(-3450 4225);
WIRE 16 -1 (-3550 4275)(-3550 4225);
WIRE 16 -1 (-3550 4275)(-3450 4275);
WIRE 16 -1 (-3550 4325)(-3550 4275);
WIRE 16 -1 (-3550 4375)(-3550 4325);
WIRE 16 -1 (-3450 4325)(-3550 4325);
WIRE 16 -1 (-3550 4375)(-3450 4375);
WIRE 16 -1 (-3550 4425)(-3550 4375);
WIRE 16 -1 (-3550 4425)(-3450 4425);
WIRE 16 -1 (-3550 4475)(-3550 4425);
WIRE 16 -1 (-3550 4475)(-3450 4475);
WIRE 16 -1 (-3550 4525)(-3550 4475);
WIRE 16 -1 (-3550 4525)(-3450 4525);
WIRE 16 -1 (-3550 4575)(-3550 4525);
WIRE 16 -1 (-3550 4625)(-3550 4575);
WIRE 16 -1 (-3550 4575)(-3450 4575);
WIRE 16 -1 (-3450 4625)(-3550 4625);
WIRE 16 -1 (-3550 4675)(-3550 4625);
WIRE 16 -1 (-3550 4675)(-3450 4675);
WIRE 16 -1 (-3550 4725)(-3550 4675);
WIRE 16 -1 (-3550 4725)(-3450 4725);
WIRE 16 -1 (-3550 4775)(-3550 4725);
WIRE 16 -1 (-3550 4775)(-3450 4775);
WIRE 16 -1 (-3550 4825)(-3550 4775);
WIRE 16 -1 (-3550 4875)(-3550 4825);
WIRE 16 -1 (-3550 4825)(-3450 4825);
WIRE 16 -1 (-3550 4875)(-3450 4875);
WIRE 16 -1 (-3550 4925)(-3550 4875);
WIRE 16 -1 (-3450 4925)(-3550 4925);
WIRE 16 -1 (-3550 4975)(-3550 4925);
WIRE 16 -1 (-3550 4975)(-3450 4975);
WIRE 16 -1 (-3550 5025)(-3550 4975);
WIRE 16 -1 (-3550 5025)(-3450 5025);
WIRE 16 -1 (-3550 5075)(-3550 5025);
WIRE 16 -1 (-3550 5125)(-3550 5075);
WIRE 16 -1 (-3550 5075)(-3450 5075);
WIRE 16 -1 (-3550 5125)(-3450 5125);
WIRE 16 -1 (-3550 5175)(-3550 5125);
WIRE 16 -1 (-3550 5175)(-3450 5175);
WIRE 16 -1 (-3550 5225)(-3550 5175);
WIRE 16 -1 (-3450 5225)(-3550 5225);
WIRE 16 -1 (-3550 5275)(-3550 5225);
WIRE 16 -1 (-3550 5275)(-3450 5275);
WIRE 16 -1 (-3550 5325)(-3550 5275);
WIRE 16 -1 (-3550 5325)(-3450 5325);
WIRE 16 -1 (-3550 5375)(-3550 5325);
WIRE 16 -1 (-3550 5425)(-3550 5375);
WIRE 16 -1 (-3550 5375)(-3450 5375);
WIRE 16 -1 (-3550 5425)(-3450 5425);
WIRE 16 -1 (-3550 5475)(-3550 5425);
WIRE 16 -1 (-3550 5475)(-3450 5475);
WIRE 16 -1 (-3550 5525)(-3550 5475);
WIRE 16 -1 (-3450 5525)(-3550 5525);
WIRE 16 -1 (-3550 5575)(-3550 5525);
WIRE 16 -1 (-3550 5575)(-3450 5575);
WIRE 16 -1 (-3550 5625)(-3550 5575);
WIRE 16 -1 (-3550 5675)(-3550 5625);
WIRE 16 -1 (-3550 5625)(-3450 5625);
WIRE 16 -1 (-3550 5675)(-3450 5675);
WIRE 16 -1 (-3550 5725)(-3550 5675);
WIRE 16 -1 (-3550 5725)(-3450 5725);
WIRE 16 -1 (-3550 5775)(-3550 5725);
WIRE 16 -1 (-3550 5775)(-3450 5775);
WIRE 16 -1 (-3550 5825)(-3550 5775);
WIRE 16 -1 (-3450 5825)(-3550 5825);
WIRE 16 -1 (-3550 5875)(-3550 5825);
WIRE 16 -1 (-3550 5925)(-3550 5875);
WIRE 16 -1 (-3550 5875)(-3450 5875);
WIRE 16 -1 (-3550 5925)(-3450 5925);
WIRE 16 -1 (-3550 5975)(-3550 5925);
WIRE 16 -1 (-3550 5975)(-3450 5975);
WIRE 16 -1 (-3550 6025)(-3550 5975);
WIRE 16 -1 (-3550 6025)(-3450 6025);
WIRE 16 -1 (-3550 6075)(-3550 6025);
WIRE 16 -1 (-3550 6075)(-3450 6075);
WIRE 16 -1 (-3550 6125)(-3550 6075);
WIRE 16 -1 (-3550 6175)(-3550 6125);
WIRE 16 -1 (-3450 6125)(-3550 6125);
WIRE 16 -1 (-3550 6175)(-3450 6175);
WIRE 16 -1 (-3550 6225)(-3550 6175);
WIRE 16 -1 (-3550 6225)(-3450 6225);
WIRE 16 -1 (-3550 6275)(-3550 6225);
WIRE 16 -1 (-3550 6275)(-3450 6275);
WIRE 16 -1 (-3550 6325)(-3550 6275);
WIRE 16 -1 (-3550 6325)(-3450 6325);
WIRE 16 -1 (-3550 6375)(-3550 6325);
WIRE 16 -1 (-3550 6425)(-3550 6375);
WIRE 16 -1 (-3550 6375)(-3450 6375);
WIRE 16 -1 (-3450 6425)(-3550 6425);
WIRE 16 -1 (-3550 6475)(-3550 6425);
WIRE 16 -1 (-3450 6475)(-3550 6475);
WIRE 16 -1 (-3550 6525)(-3550 6475);
WIRE 16 -1 (-3725 1125)(-3450 1125);
WIRE 16 -1 (-3725 1475)(-3725 1125);
WIRE 16 -1 (-3725 1475)(-3450 1475);
WIRE 16 -1 (-3725 1525)(-3725 1475);
WIRE 16 -1 (-3725 1525)(-3450 1525);
WIRE 16 -1 (-3725 1575)(-3725 1525);
WIRE 16 -1 (-3725 1575)(-3450 1575);
WIRE 16 -1 (-3725 1625)(-3725 1575);
WIRE 16 -1 (-3725 1625)(-3450 1625);
WIRE 16 -1 (-3725 1675)(-3725 1625);
WIRE 16 -1 (-3725 1675)(-3450 1675);
WIRE 16 -1 (-3725 1725)(-3725 1675);
WIRE 16 -1 (-3725 1725)(-3450 1725);
WIRE 16 -1 (-3725 1775)(-3725 1725);
WIRE 16 -1 (-3725 1775)(-3450 1775);
WIRE 16 -1 (-3725 1825)(-3725 1775);
WIRE 16 -1 (-3725 1825)(-3450 1825);
WIRE 16 -1 (-3725 1875)(-3725 1825);
WIRE 16 -1 (-3725 1875)(-3450 1875);
WIRE 16 -1 (-3725 1925)(-3725 1875);
WIRE 16 -1 (-3725 1925)(-3450 1925);
WIRE 16 -1 (-3725 1975)(-3725 1925);
WIRE 16 -1 (-3725 1975)(-3450 1975);
WIRE 16 -1 (-3725 2025)(-3725 1975);
WIRE 16 -1 (-3725 2025)(-3725 2075);
WIRE 16 -1 (-3725 2025)(-3450 2025);
WIRE 16 -1 (-3725 2075)(-3450 2075);
WIRE 16 -1 (-3725 2125)(-3725 2075);
WIRE 16 -1 (-3725 2125)(-3450 2125);
WIRE 16 -1 (-3725 2175)(-3725 2125);
WIRE 16 -1 (-3725 2175)(-3450 2175);
WIRE 16 -1 (-3725 2225)(-3725 2175);
WIRE 16 -1 (-3725 2225)(-3450 2225);
WIRE 16 -1 (-3725 2275)(-3725 2225);
WIRE 16 -1 (-3725 2275)(-3450 2275);
WIRE 16 -1 (-3725 2325)(-3725 2275);
WIRE 16 -1 (-3725 2325)(-3450 2325);
WIRE 16 -1 (-3725 2375)(-3725 2325);
WIRE 16 -1 (-3725 2375)(-3450 2375);
WIRE 16 -1 (-3725 2425)(-3725 2375);
WIRE 16 -1 (-3725 2425)(-3450 2425);
WIRE 16 -1 (-3725 2475)(-3725 2425);
WIRE 16 -1 (-3725 2475)(-3450 2475);
WIRE 16 -1 (-3725 2575)(-3725 2475);
WIRE 16 -1 (-3450 2575)(-3725 2575);
WIRE 16 -1 (-3725 2650)(-3725 2575);
WIRE 16 -1 (-3725 875)(-3450 875);
WIRE 16 -1 (-3725 825)(-3725 875);
WIRE 16 -1 (-3725 1000)(-3725 875);
WIRE 16 -1 (-3450 825)(-3725 825);
WIRE 16 -1 (-3825 3675)(-3825 3625);
WIRE 16 -1 (-3825 3725)(-3825 3675);
WIRE 16 -1 (-3825 3675)(-3875 3675);
WIRE 16 -1 (-3825 3625)(-3875 3625);
WIRE 16 -1 (-3825 3625)(-3825 3575);
WIRE 16 -1 (-3825 3575)(-3875 3575);
WIRE 16 -1 (-3825 3775)(-3825 3725);
WIRE 16 -1 (-3825 3725)(-3875 3725);
WIRE 16 -1 (-3825 3825)(-3825 3775);
WIRE 16 -1 (-3825 3775)(-3875 3775);
WIRE 16 -1 (-3825 3875)(-3825 3825);
WIRE 16 -1 (-3825 3825)(-3875 3825);
WIRE 16 -1 (-3825 3925)(-3825 3875);
WIRE 16 -1 (-3825 3875)(-3875 3875);
WIRE 16 -1 (-3825 3975)(-3825 3925);
WIRE 16 -1 (-3825 3925)(-3875 3925);
WIRE 16 -1 (-3825 4025)(-3825 3975);
WIRE 16 -1 (-3825 3975)(-3875 3975);
WIRE 16 -1 (-3825 4075)(-3825 4025);
WIRE 16 -1 (-3825 4025)(-3875 4025);
WIRE 16 -1 (-3825 4125)(-3825 4075);
WIRE 16 -1 (-3825 4075)(-3875 4075);
WIRE 16 -1 (-3825 4175)(-3825 4125);
WIRE 16 -1 (-3825 4125)(-3875 4125);
WIRE 16 -1 (-3825 4225)(-3825 4175);
WIRE 16 -1 (-3825 4175)(-3875 4175);
WIRE 16 -1 (-3825 4275)(-3825 4225);
WIRE 16 -1 (-3825 4225)(-3875 4225);
WIRE 16 -1 (-3825 4325)(-3825 4275);
WIRE 16 -1 (-3825 4275)(-3875 4275);
WIRE 16 -1 (-3825 4375)(-3825 4325);
WIRE 16 -1 (-3825 4325)(-3875 4325);
WIRE 16 -1 (-3825 4425)(-3825 4375);
WIRE 16 -1 (-3825 4375)(-3875 4375);
WIRE 16 -1 (-3825 4475)(-3825 4425);
WIRE 16 -1 (-3825 4425)(-3875 4425);
WIRE 16 -1 (-3825 4525)(-3825 4475);
WIRE 16 -1 (-3825 4475)(-3875 4475);
WIRE 16 -1 (-3825 4575)(-3825 4525);
WIRE 16 -1 (-3825 4525)(-3875 4525);
WIRE 16 -1 (-3825 4625)(-3825 4575);
WIRE 16 -1 (-3825 4575)(-3875 4575);
WIRE 16 -1 (-3825 4675)(-3825 4625);
WIRE 16 -1 (-3825 4625)(-3875 4625);
WIRE 16 -1 (-3825 4725)(-3825 4675);
WIRE 16 -1 (-3825 4675)(-3875 4675);
WIRE 16 -1 (-3825 4775)(-3825 4725);
WIRE 16 -1 (-3825 4725)(-3875 4725);
WIRE 16 -1 (-3825 4825)(-3825 4775);
WIRE 16 -1 (-3825 4775)(-3875 4775);
WIRE 16 -1 (-3825 4875)(-3825 4825);
WIRE 16 -1 (-3825 4825)(-3875 4825);
WIRE 16 -1 (-3825 4925)(-3825 4875);
WIRE 16 -1 (-3825 4875)(-3875 4875);
WIRE 16 -1 (-3825 4975)(-3825 4925);
WIRE 16 -1 (-3825 4925)(-3875 4925);
WIRE 16 -1 (-3825 5025)(-3825 4975);
WIRE 16 -1 (-3825 4975)(-3875 4975);
WIRE 16 -1 (-3825 5075)(-3825 5025);
WIRE 16 -1 (-3825 5025)(-3875 5025);
WIRE 16 -1 (-3825 5125)(-3825 5075);
WIRE 16 -1 (-3825 5075)(-3875 5075);
WIRE 16 -1 (-3825 5175)(-3825 5125);
WIRE 16 -1 (-3825 5125)(-3875 5125);
WIRE 16 -1 (-3825 5225)(-3825 5175);
WIRE 16 -1 (-3825 5175)(-3875 5175);
WIRE 16 -1 (-3825 5275)(-3825 5225);
WIRE 16 -1 (-3825 5225)(-3875 5225);
WIRE 16 -1 (-3825 5325)(-3825 5275);
WIRE 16 -1 (-3825 5275)(-3875 5275);
WIRE 16 -1 (-3825 5375)(-3825 5325);
WIRE 16 -1 (-3825 5325)(-3875 5325);
WIRE 16 -1 (-3825 5425)(-3825 5375);
WIRE 16 -1 (-3825 5375)(-3875 5375);
WIRE 16 -1 (-3825 5475)(-3825 5425);
WIRE 16 -1 (-3825 5425)(-3875 5425);
WIRE 16 -1 (-3825 5525)(-3825 5475);
WIRE 16 -1 (-3825 5475)(-3875 5475);
WIRE 16 -1 (-3825 5575)(-3825 5525);
WIRE 16 -1 (-3825 5525)(-3875 5525);
WIRE 16 -1 (-3825 5625)(-3825 5575);
WIRE 16 -1 (-3825 5575)(-3875 5575);
WIRE 16 -1 (-3825 5675)(-3825 5625);
WIRE 16 -1 (-3825 5625)(-3875 5625);
WIRE 16 -1 (-3825 5725)(-3825 5675);
WIRE 16 -1 (-3825 5675)(-3875 5675);
WIRE 16 -1 (-3825 5775)(-3825 5725);
WIRE 16 -1 (-3825 5725)(-3875 5725);
WIRE 16 -1 (-3825 5825)(-3825 5775);
WIRE 16 -1 (-3825 5775)(-3875 5775);
WIRE 16 -1 (-3825 5875)(-3825 5825);
WIRE 16 -1 (-3825 5825)(-3875 5825);
WIRE 16 -1 (-3825 5925)(-3825 5875);
WIRE 16 -1 (-3825 5875)(-3875 5875);
WIRE 16 -1 (-3825 5975)(-3825 5925);
WIRE 16 -1 (-3825 5925)(-3875 5925);
WIRE 16 -1 (-3825 6025)(-3825 5975);
WIRE 16 -1 (-3825 5975)(-3875 5975);
WIRE 16 -1 (-3825 6075)(-3825 6025);
WIRE 16 -1 (-3825 6025)(-3875 6025);
WIRE 16 -1 (-3825 6125)(-3825 6075);
WIRE 16 -1 (-3825 6075)(-3875 6075);
WIRE 16 -1 (-3875 6125)(-3825 6125);
WIRE 16 -1 (-3825 6125)(-3825 6200);
WIRE 16 -1 (-5125 3175)(-5075 3175);
WIRE 16 -1 (-5125 3225)(-5125 3175);
WIRE 16 -1 (-5125 3225)(-5075 3225);
WIRE 16 -1 (-5125 3275)(-5125 3225);
WIRE 16 -1 (-5125 3275)(-5075 3275);
WIRE 16 -1 (-5125 3325)(-5125 3275);
WIRE 16 -1 (-5125 3325)(-5075 3325);
WIRE 16 -1 (-5125 3375)(-5125 3325);
WIRE 16 -1 (-5125 3375)(-5075 3375);
WIRE 16 -1 (-5125 3425)(-5125 3375);
WIRE 16 -1 (-5125 3425)(-5075 3425);
WIRE 16 -1 (-5125 3475)(-5125 3425);
WIRE 16 -1 (-5125 3475)(-5075 3475);
WIRE 16 -1 (-5125 3525)(-5125 3475);
WIRE 16 -1 (-5125 3525)(-5075 3525);
WIRE 16 -1 (-5125 3575)(-5125 3525);
WIRE 16 -1 (-5125 3575)(-5075 3575);
WIRE 16 -1 (-5125 3625)(-5125 3575);
WIRE 16 -1 (-5125 3625)(-5075 3625);
WIRE 16 -1 (-5125 3675)(-5125 3625);
WIRE 16 -1 (-5125 3675)(-5075 3675);
WIRE 16 -1 (-5125 3725)(-5125 3675);
WIRE 16 -1 (-5125 3725)(-5075 3725);
WIRE 16 -1 (-5125 3775)(-5125 3725);
WIRE 16 -1 (-5125 3775)(-5075 3775);
WIRE 16 -1 (-5125 3825)(-5125 3775);
WIRE 16 -1 (-5125 3825)(-5075 3825);
WIRE 16 -1 (-5125 3875)(-5125 3825);
WIRE 16 -1 (-5125 3875)(-5075 3875);
WIRE 16 -1 (-5125 3925)(-5125 3875);
WIRE 16 -1 (-5125 3925)(-5075 3925);
WIRE 16 -1 (-5125 3975)(-5125 3925);
WIRE 16 -1 (-5125 3975)(-5075 3975);
WIRE 16 -1 (-5125 4025)(-5125 3975);
WIRE 16 -1 (-5125 4025)(-5075 4025);
WIRE 16 -1 (-5125 4075)(-5125 4025);
WIRE 16 -1 (-5125 4125)(-5125 4075);
WIRE 16 -1 (-5125 4075)(-5075 4075);
WIRE 16 -1 (-5125 4125)(-5075 4125);
WIRE 16 -1 (-5125 4175)(-5125 4125);
WIRE 16 -1 (-5125 4175)(-5075 4175);
WIRE 16 -1 (-5125 4225)(-5125 4175);
WIRE 16 -1 (-5125 4225)(-5075 4225);
WIRE 16 -1 (-5125 4275)(-5125 4225);
WIRE 16 -1 (-5125 4275)(-5075 4275);
WIRE 16 -1 (-5125 4325)(-5125 4275);
WIRE 16 -1 (-5125 4325)(-5075 4325);
WIRE 16 -1 (-5125 4375)(-5125 4325);
WIRE 16 -1 (-5125 4375)(-5075 4375);
WIRE 16 -1 (-5125 4425)(-5125 4375);
WIRE 16 -1 (-5125 4425)(-5075 4425);
WIRE 16 -1 (-5125 4475)(-5125 4425);
WIRE 16 -1 (-5125 4475)(-5075 4475);
WIRE 16 -1 (-5125 4525)(-5125 4475);
WIRE 16 -1 (-5125 4525)(-5075 4525);
WIRE 16 -1 (-5125 4575)(-5125 4525);
WIRE 16 -1 (-5125 4575)(-5075 4575);
WIRE 16 -1 (-5125 4625)(-5125 4575);
WIRE 16 -1 (-5125 4625)(-5075 4625);
WIRE 16 -1 (-5125 4675)(-5125 4625);
WIRE 16 -1 (-5125 4675)(-5075 4675);
WIRE 16 -1 (-5125 4725)(-5125 4675);
WIRE 16 -1 (-5125 4725)(-5075 4725);
WIRE 16 -1 (-5125 4775)(-5125 4725);
WIRE 16 -1 (-5125 4775)(-5075 4775);
WIRE 16 -1 (-5125 4825)(-5125 4775);
WIRE 16 -1 (-5125 4825)(-5075 4825);
WIRE 16 -1 (-5125 4875)(-5125 4825);
WIRE 16 -1 (-5125 4875)(-5075 4875);
WIRE 16 -1 (-5125 4925)(-5125 4875);
WIRE 16 -1 (-5125 4925)(-5075 4925);
WIRE 16 -1 (-5125 4975)(-5125 4925);
WIRE 16 -1 (-5125 4975)(-5075 4975);
WIRE 16 -1 (-5125 5025)(-5125 4975);
WIRE 16 -1 (-5125 5025)(-5075 5025);
WIRE 16 -1 (-5125 5075)(-5125 5025);
WIRE 16 -1 (-5125 5075)(-5075 5075);
WIRE 16 -1 (-5125 5125)(-5125 5075);
WIRE 16 -1 (-5125 5125)(-5075 5125);
WIRE 16 -1 (-5125 5175)(-5125 5125);
WIRE 16 -1 (-5125 5175)(-5075 5175);
WIRE 16 -1 (-5125 5225)(-5125 5175);
WIRE 16 -1 (-5125 5225)(-5075 5225);
WIRE 16 -1 (-5125 5275)(-5125 5225);
WIRE 16 -1 (-5125 5275)(-5075 5275);
WIRE 16 -1 (-5125 5325)(-5125 5275);
WIRE 16 -1 (-5125 5325)(-5075 5325);
WIRE 16 -1 (-5125 5375)(-5125 5325);
WIRE 16 -1 (-5125 5375)(-5075 5375);
WIRE 16 -1 (-5125 5425)(-5125 5375);
WIRE 16 -1 (-5125 5425)(-5075 5425);
WIRE 16 -1 (-5125 5475)(-5125 5425);
WIRE 16 -1 (-5125 5475)(-5075 5475);
WIRE 16 -1 (-5125 5525)(-5125 5475);
WIRE 16 -1 (-5125 5525)(-5075 5525);
WIRE 16 -1 (-5125 5575)(-5125 5525);
WIRE 16 -1 (-5125 5575)(-5075 5575);
WIRE 16 -1 (-5125 5625)(-5125 5575);
WIRE 16 -1 (-5125 5625)(-5075 5625);
WIRE 16 -1 (-5125 5675)(-5125 5625);
WIRE 16 -1 (-5125 5675)(-5075 5675);
WIRE 16 -1 (-5125 5725)(-5125 5675);
WIRE 16 -1 (-5125 5725)(-5075 5725);
WIRE 16 -1 (-5125 5775)(-5125 5725);
WIRE 16 -1 (-5125 5775)(-5075 5775);
WIRE 16 -1 (-5125 5825)(-5125 5775);
WIRE 16 -1 (-5125 5825)(-5075 5825);
WIRE 16 -1 (-5125 5875)(-5125 5825);
WIRE 16 -1 (-5125 5875)(-5075 5875);
WIRE 16 -1 (-5125 5925)(-5125 5875);
WIRE 16 -1 (-5125 5925)(-5075 5925);
WIRE 16 -1 (-5125 5975)(-5125 5925);
WIRE 16 -1 (-5125 5975)(-5075 5975);
WIRE 16 -1 (-5125 6025)(-5125 5975);
WIRE 16 -1 (-5125 6025)(-5075 6025);
WIRE 16 -1 (-5125 6075)(-5125 6025);
WIRE 16 -1 (-5125 6075)(-5075 6075);
WIRE 16 -1 (-5125 6125)(-5125 6075);
WIRE 16 -1 (-5125 6200)(-5125 6125);
WIRE 16 -1 (-5125 6125)(-5075 6125);
WIRE 16 -1 (-1125 575)(-1125 625);
WIRE 16 -1 (-1450 575)(-1125 575);
WIRE 16 -1 (-1450 575)(-1450 625);
WIRE 16 -1 (-2150 575)(-1450 575);
FORCEPROP 2 LAST SIG_NAME CPU1_VDDBT_RTC_G
J 0
(-2010 585);
DISPLAY 0.489362 (-2010 585);
FORCEPROP 2 LASTPROP $XRERR UNIQUE?
J 0
(-2250 585);
DISPLAY 0.638298 (-2250 585);
PAINT MONO (-2250 585);
DISPLAY INVISIBLE (-2250 585);
DOT 1 (-2050 1025);
DOT 1 (-3725 875);
DOT 1 (-2050 1525);
DOT 1 (-2050 3025);
DOT 1 (-2050 3075);
DOT 1 (-2050 3125);
DOT 1 (-6950 5675);
DOT 1 (-7425 1900);
DOT 1 (-5525 3175);
DOT 1 (-5525 3125);
DOT 1 (-5525 2725);
DOT 1 (-5125 3225);
DOT 1 (-5125 3325);
DOT 1 (-5125 3275);
DOT 1 (-5125 3375);
DOT 1 (-5125 3425);
DOT 1 (-5125 3475);
DOT 1 (-5125 3525);
DOT 1 (-5125 3575);
DOT 1 (-5125 3625);
DOT 1 (-5125 3675);
DOT 1 (-5125 3725);
DOT 1 (-5125 3775);
DOT 1 (-5125 3825);
DOT 1 (-5125 3875);
DOT 1 (-5125 3925);
DOT 1 (-5125 3975);
DOT 1 (-5125 4075);
DOT 1 (-5125 4025);
DOT 1 (-5125 4125);
DOT 1 (-5125 4175);
DOT 1 (-5125 4225);
DOT 1 (-3825 3625);
DOT 1 (-3825 3675);
DOT 1 (-3825 3725);
DOT 1 (-3825 3775);
DOT 1 (-3825 3825);
DOT 1 (-3825 3875);
DOT 1 (-3825 3925);
DOT 1 (-3825 3975);
DOT 1 (-3825 4025);
DOT 1 (-3825 4075);
DOT 1 (-3825 4125);
DOT 1 (-3825 4175);
DOT 1 (-3825 4225);
DOT 1 (-5125 4275);
DOT 1 (-3825 4275);
DOT 1 (-5125 4325);
DOT 1 (-5125 4375);
DOT 1 (-5125 4425);
DOT 1 (-5125 4475);
DOT 1 (-5125 4525);
DOT 1 (-5125 4575);
DOT 1 (-5125 4625);
DOT 1 (-5125 4675);
DOT 1 (-5125 4725);
DOT 1 (-5125 4775);
DOT 1 (-5125 4875);
DOT 1 (-5125 4825);
DOT 1 (-5125 4925);
DOT 1 (-5125 4975);
DOT 1 (-5125 5025);
DOT 1 (-5125 5125);
DOT 1 (-5125 5075);
DOT 1 (-5125 5175);
DOT 1 (-5125 5225);
DOT 1 (-5125 5275);
DOT 1 (-5125 5375);
DOT 1 (-5125 5325);
DOT 1 (-5125 5425);
DOT 1 (-5125 5475);
DOT 1 (-5125 5525);
DOT 1 (-5125 5625);
DOT 1 (-5125 5675);
DOT 1 (-5125 5575);
DOT 1 (-5125 5725);
DOT 1 (-5125 5775);
DOT 1 (-5125 5825);
DOT 1 (-5125 5875);
DOT 1 (-5125 5925);
DOT 1 (-5125 5975);
DOT 1 (-5125 6025);
DOT 1 (-5125 6075);
DOT 1 (-5125 6125);
DOT 1 (-3825 4325);
DOT 1 (-3825 4375);
DOT 1 (-3825 4425);
DOT 1 (-3825 4475);
DOT 1 (-3825 4525);
DOT 1 (-3825 4575);
DOT 1 (-3825 4625);
DOT 1 (-3825 4675);
DOT 1 (-3825 4725);
DOT 1 (-3825 4775);
DOT 1 (-3825 4825);
DOT 1 (-3825 4875);
DOT 1 (-3825 4925);
DOT 1 (-3825 4975);
DOT 1 (-3825 5025);
DOT 1 (-3825 5075);
DOT 1 (-3825 5125);
DOT 1 (-3825 5175);
DOT 1 (-3825 5225);
DOT 1 (-3825 5275);
DOT 1 (-3825 5325);
DOT 1 (-3825 5375);
DOT 1 (-3825 5425);
DOT 1 (-3825 5475);
DOT 1 (-3825 5525);
DOT 1 (-3825 5575);
DOT 1 (-3825 5625);
DOT 1 (-3825 5675);
DOT 1 (-3825 5725);
DOT 1 (-3825 5775);
DOT 1 (-3825 5825);
DOT 1 (-3825 5875);
DOT 1 (-3825 5925);
DOT 1 (-3825 5975);
DOT 1 (-3825 6025);
DOT 1 (-3825 6075);
DOT 1 (-3825 6125);
DOT 1 (-3550 4875);
DOT 1 (-7425 3050);
DOT 1 (-7425 4350);
DOT 1 (-7425 4400);
DOT 1 (-6950 5925);
DOT 1 (-2050 2725);
DOT 1 (-2050 2675);
DOT 1 (-2050 3775);
DOT 1 (-2050 3875);
DOT 1 (-3550 4675);
DOT 1 (-7425 6300);
DOT 1 (-7425 6200);
DOT 1 (-7425 6250);
DOT 1 (-7425 6150);
DOT 1 (-7425 6100);
DOT 1 (-7425 6050);
DOT 1 (-7425 6000);
DOT 1 (-7425 5950);
DOT 1 (-7425 5900);
DOT 1 (-7425 5800);
DOT 1 (-7425 5850);
DOT 1 (-7425 5750);
DOT 1 (-7425 5700);
DOT 1 (-7425 5650);
DOT 1 (-7425 5550);
DOT 1 (-7425 5600);
DOT 1 (-7425 5500);
DOT 1 (-7425 5400);
DOT 1 (-7425 5450);
DOT 1 (-7425 5300);
DOT 1 (-7425 5350);
DOT 1 (-7425 5250);
DOT 1 (-7425 5200);
DOT 1 (-7425 5150);
DOT 1 (-7425 5050);
DOT 1 (-7425 5100);
DOT 1 (-7425 5000);
DOT 1 (-7425 4950);
DOT 1 (-7425 4900);
DOT 1 (-7425 4850);
DOT 1 (-7425 4800);
DOT 1 (-7425 4750);
DOT 1 (-7425 4650);
DOT 1 (-7425 4700);
DOT 1 (-7425 4600);
DOT 1 (-7425 4550);
DOT 1 (-7425 4500);
DOT 1 (-7425 4450);
DOT 1 (-7425 4300);
DOT 1 (-7425 4250);
DOT 1 (-7425 4150);
DOT 1 (-7425 4200);
DOT 1 (-7425 4100);
DOT 1 (-7425 4050);
DOT 1 (-7425 4000);
DOT 1 (-7425 3900);
DOT 1 (-7425 3950);
DOT 1 (-7425 3750);
DOT 1 (-7425 3800);
DOT 1 (-7425 3850);
DOT 1 (-7425 3700);
DOT 1 (-7425 3650);
DOT 1 (-7425 3600);
DOT 1 (-7425 3500);
DOT 1 (-7425 3550);
DOT 1 (-7425 3450);
DOT 1 (-7425 3400);
DOT 1 (-7425 3350);
DOT 1 (-7425 3250);
DOT 1 (-7425 3300);
DOT 1 (-7425 3200);
DOT 1 (-7425 3150);
DOT 1 (-7425 3100);
DOT 1 (-7425 3000);
DOT 1 (-8875 6350);
DOT 1 (-8875 6300);
DOT 1 (-8875 6250);
DOT 1 (-8875 6200);
DOT 1 (-8875 6150);
DOT 1 (-8875 6100);
DOT 1 (-8875 6050);
DOT 1 (-8875 6000);
DOT 1 (-8875 5950);
DOT 1 (-8875 5900);
DOT 1 (-8875 5850);
DOT 1 (-8875 5800);
DOT 1 (-8875 5750);
DOT 1 (-8875 5700);
DOT 1 (-8875 5650);
DOT 1 (-8875 5600);
DOT 1 (-8875 5550);
DOT 1 (-8875 5500);
DOT 1 (-8875 5450);
DOT 1 (-8875 5400);
DOT 1 (-8875 5350);
DOT 1 (-8875 5300);
DOT 1 (-8875 5250);
DOT 1 (-8875 5200);
DOT 1 (-8875 5150);
DOT 1 (-8875 5100);
DOT 1 (-8875 5050);
DOT 1 (-8875 5000);
DOT 1 (-8875 4950);
DOT 1 (-8875 4900);
DOT 1 (-8875 4850);
DOT 1 (-8875 4800);
DOT 1 (-8875 4750);
DOT 1 (-8875 4700);
DOT 1 (-8875 4650);
DOT 1 (-8875 4600);
DOT 1 (-8875 4550);
DOT 1 (-8875 4500);
DOT 1 (-8875 4450);
DOT 1 (-8875 4400);
DOT 1 (-8875 4350);
DOT 1 (-8875 4300);
DOT 1 (-8875 4250);
DOT 1 (-8875 4200);
DOT 1 (-8875 4150);
DOT 1 (-8875 4100);
DOT 1 (-8875 4050);
DOT 1 (-8875 4000);
DOT 1 (-8875 3950);
DOT 1 (-8875 3900);
DOT 1 (-8875 3850);
DOT 1 (-8875 3800);
DOT 1 (-8875 3750);
DOT 1 (-8875 3700);
DOT 1 (-8875 3650);
DOT 1 (-8875 3600);
DOT 1 (-8875 3550);
DOT 1 (-8875 3500);
DOT 1 (-8875 3450);
DOT 1 (-8875 3400);
DOT 1 (-8875 3350);
DOT 1 (-8875 3300);
DOT 1 (-8875 3250);
DOT 1 (-8875 3200);
DOT 1 (-8875 3150);
DOT 1 (-8875 3100);
DOT 1 (-8875 3050);
DOT 1 (-8875 3000);
DOT 1 (-7425 2950);
DOT 1 (-7425 2900);
DOT 1 (-7425 2850);
DOT 1 (-7425 2800);
DOT 1 (-7425 2750);
DOT 1 (-7425 2700);
DOT 1 (-7425 2600);
DOT 1 (-7425 2650);
DOT 1 (-7425 2550);
DOT 1 (-7425 2500);
DOT 1 (-7425 2450);
DOT 1 (-7425 2350);
DOT 1 (-7425 2400);
DOT 1 (-7425 2200);
DOT 1 (-7425 2250);
DOT 1 (-7425 2100);
DOT 1 (-7425 2150);
DOT 1 (-7425 2050);
DOT 1 (-7425 2000);
DOT 1 (-7425 1950);
DOT 1 (-7425 1850);
DOT 1 (-7425 1800);
DOT 1 (-7425 1750);
DOT 1 (-7425 1700);
DOT 1 (-7425 1650);
DOT 1 (-7425 1600);
DOT 1 (-7425 1550);
DOT 1 (-7425 1450);
DOT 1 (-7425 1500);
DOT 1 (-7425 1400);
DOT 1 (-7425 1350);
DOT 1 (-7425 1300);
DOT 1 (-7425 1200);
DOT 1 (-7425 1250);
DOT 1 (-7425 1150);
DOT 1 (-7425 1100);
DOT 1 (-7425 1050);
DOT 1 (-7425 950);
DOT 1 (-7425 1000);
DOT 1 (-7425 900);
DOT 1 (-7425 850);
DOT 1 (-7425 800);
DOT 1 (-7425 700);
DOT 1 (-7425 750);
DOT 1 (-7425 600);
DOT 1 (-7425 650);
DOT 1 (-8875 2950);
DOT 1 (-8875 2900);
DOT 1 (-8875 2850);
DOT 1 (-8875 2800);
DOT 1 (-8875 2750);
DOT 1 (-8875 2700);
DOT 1 (-8875 2650);
DOT 1 (-8875 2600);
DOT 1 (-8875 2550);
DOT 1 (-8875 2500);
DOT 1 (-8875 2450);
DOT 1 (-8875 2400);
DOT 1 (-8875 2350);
DOT 1 (-8875 2300);
DOT 1 (-8875 2250);
DOT 1 (-8875 2200);
DOT 1 (-8875 2150);
DOT 1 (-8875 2100);
DOT 1 (-8875 2050);
DOT 1 (-8875 2000);
DOT 1 (-8875 1950);
DOT 1 (-8875 1900);
DOT 1 (-8875 1850);
DOT 1 (-8875 1800);
DOT 1 (-8875 1750);
DOT 1 (-8875 1700);
DOT 1 (-8875 1650);
DOT 1 (-8875 1600);
DOT 1 (-8875 1550);
DOT 1 (-8875 1500);
DOT 1 (-8875 1450);
DOT 1 (-8875 1400);
DOT 1 (-8875 1350);
DOT 1 (-8875 1300);
DOT 1 (-8875 1250);
DOT 1 (-8875 1200);
DOT 1 (-8875 1150);
DOT 1 (-8875 1100);
DOT 1 (-8875 1050);
DOT 1 (-8875 1000);
DOT 1 (-8875 950);
DOT 1 (-8875 900);
DOT 1 (-8875 850);
DOT 1 (-8875 800);
DOT 1 (-8875 750);
DOT 1 (-8875 700);
DOT 1 (-8875 650);
DOT 1 (-7425 2300);
DOT 1 (-5525 6425);
DOT 1 (-5525 6375);
DOT 1 (-5525 6325);
DOT 1 (-5525 6275);
DOT 1 (-5525 6225);
DOT 1 (-5525 6175);
DOT 1 (-5525 6125);
DOT 1 (-5525 6075);
DOT 1 (-5525 6025);
DOT 1 (-5525 5975);
DOT 1 (-5525 5925);
DOT 1 (-5525 5875);
DOT 1 (-5525 5825);
DOT 1 (-5525 5775);
DOT 1 (-5525 5725);
DOT 1 (-5525 5675);
DOT 1 (-5525 5625);
DOT 1 (-5525 5575);
DOT 1 (-5525 5525);
DOT 1 (-5525 5475);
DOT 1 (-5525 5425);
DOT 1 (-5525 5375);
DOT 1 (-5525 5325);
DOT 1 (-5525 5275);
DOT 1 (-5525 5225);
DOT 1 (-5525 5175);
DOT 1 (-5525 5125);
DOT 1 (-5525 5075);
DOT 1 (-5525 5025);
DOT 1 (-5525 4975);
DOT 1 (-5525 4925);
DOT 1 (-5525 4875);
DOT 1 (-5525 4825);
DOT 1 (-5525 4775);
DOT 1 (-5525 4725);
DOT 1 (-5525 4675);
DOT 1 (-5525 4625);
DOT 1 (-5525 4575);
DOT 1 (-5525 4525);
DOT 1 (-5525 4475);
DOT 1 (-5525 4425);
DOT 1 (-5525 4375);
DOT 1 (-5525 4325);
DOT 1 (-5525 4275);
DOT 1 (-5525 4225);
DOT 1 (-5525 4175);
DOT 1 (-5525 4125);
DOT 1 (-5525 4075);
DOT 1 (-5525 4025);
DOT 1 (-5525 3975);
DOT 1 (-5525 3925);
DOT 1 (-5525 3875);
DOT 1 (-5525 3825);
DOT 1 (-5525 3775);
DOT 1 (-5525 3725);
DOT 1 (-5525 3675);
DOT 1 (-5525 3625);
DOT 1 (-5525 3575);
DOT 1 (-5525 3525);
DOT 1 (-5525 3475);
DOT 1 (-5525 3425);
DOT 1 (-5525 3375);
DOT 1 (-5525 3325);
DOT 1 (-5525 3275);
DOT 1 (-5525 3225);
DOT 1 (-5525 3075);
DOT 1 (-5525 3025);
DOT 1 (-5525 2975);
DOT 1 (-5525 2925);
DOT 1 (-5525 2875);
DOT 1 (-5525 2825);
DOT 1 (-5525 2775);
DOT 1 (-5525 2675);
DOT 1 (-5525 2625);
DOT 1 (-5525 2575);
DOT 1 (-5525 2525);
DOT 1 (-5525 2475);
DOT 1 (-5525 2425);
DOT 1 (-5525 2375);
DOT 1 (-5525 2325);
DOT 1 (-5525 2275);
DOT 1 (-5525 2225);
DOT 1 (-5525 2175);
DOT 1 (-5525 2075);
DOT 1 (-5525 2025);
DOT 1 (-5525 1975);
DOT 1 (-5525 1925);
DOT 1 (-5525 1875);
DOT 1 (-5525 1825);
DOT 1 (-5525 1775);
DOT 1 (-5525 1725);
DOT 1 (-5525 1675);
DOT 1 (-5525 1625);
DOT 1 (-5525 1575);
DOT 1 (-5525 1525);
DOT 1 (-5525 1475);
DOT 1 (-5525 1425);
DOT 1 (-5525 1375);
DOT 1 (-5525 1325);
DOT 1 (-5525 1275);
DOT 1 (-5525 1225);
DOT 1 (-5525 1175);
DOT 1 (-5525 1125);
DOT 1 (-5525 1075);
DOT 1 (-5525 1025);
DOT 1 (-5525 975);
DOT 1 (-5525 925);
DOT 1 (-5525 875);
DOT 1 (-5525 825);
DOT 1 (-5525 675);
DOT 1 (-5525 775);
DOT 1 (-5525 725);
DOT 1 (-5525 625);
DOT 1 (-5525 575);
DOT 1 (-5525 525);
DOT 1 (-5525 475);
DOT 1 (-5525 425);
DOT 1 (-5525 325);
DOT 1 (-5525 375);
DOT 1 (-6950 6075);
DOT 1 (-6950 6125);
DOT 1 (-6950 5975);
DOT 1 (-6950 6025);
DOT 1 (-6950 5875);
DOT 1 (-6950 5825);
DOT 1 (-6950 5775);
DOT 1 (-6950 5725);
DOT 1 (-6950 5625);
DOT 1 (-6950 5575);
DOT 1 (-6950 5525);
DOT 1 (-6950 5475);
DOT 1 (-6950 5425);
DOT 1 (-6950 5375);
DOT 1 (-6950 5325);
DOT 1 (-6950 5275);
DOT 1 (-6950 5225);
DOT 1 (-6950 5175);
DOT 1 (-6950 5125);
DOT 1 (-6950 5075);
DOT 1 (-6950 5025);
DOT 1 (-6950 4925);
DOT 1 (-6950 4975);
DOT 1 (-6950 4875);
DOT 1 (-6950 4775);
DOT 1 (-6950 4825);
DOT 1 (-6950 4675);
DOT 1 (-6950 4725);
DOT 1 (-6950 4625);
DOT 1 (-6950 4525);
DOT 1 (-6950 4575);
DOT 1 (-6950 4425);
DOT 1 (-6950 4475);
DOT 1 (-6950 4375);
DOT 1 (-6950 4275);
DOT 1 (-6950 4325);
DOT 1 (-6950 4125);
DOT 1 (-6950 4175);
DOT 1 (-6950 4225);
DOT 1 (-6950 4025);
DOT 1 (-6950 4075);
DOT 1 (-6950 3875);
DOT 1 (-6950 3925);
DOT 1 (-6950 3975);
DOT 1 (-6950 3825);
DOT 1 (-6950 3775);
DOT 1 (-6950 3725);
DOT 1 (-6950 3675);
DOT 1 (-6950 3625);
DOT 1 (-6950 3575);
DOT 1 (-6950 3525);
DOT 1 (-6950 3475);
DOT 1 (-6950 3425);
DOT 1 (-6950 3375);
DOT 1 (-6950 3325);
DOT 1 (-6950 3275);
DOT 1 (-6950 3225);
DOT 1 (-6950 3175);
DOT 1 (-6950 3125);
DOT 1 (-6950 3075);
DOT 1 (-6950 3025);
DOT 1 (-6950 2975);
DOT 1 (-6950 2925);
DOT 1 (-6950 2875);
DOT 1 (-6950 2825);
DOT 1 (-6950 2775);
DOT 1 (-6950 2725);
DOT 1 (-6950 2625);
DOT 1 (-6950 2675);
DOT 1 (-6950 2575);
DOT 1 (-6950 2475);
DOT 1 (-6950 2525);
DOT 1 (-6950 2375);
DOT 1 (-6950 2425);
DOT 1 (-6950 2325);
DOT 1 (-6950 2225);
DOT 1 (-6950 2275);
DOT 1 (-6950 2075);
DOT 1 (-6950 2125);
DOT 1 (-6950 2175);
DOT 1 (-6950 1975);
DOT 1 (-6950 2025);
DOT 1 (-6950 1825);
DOT 1 (-6950 1875);
DOT 1 (-6950 1925);
DOT 1 (-6950 1775);
DOT 1 (-6950 1725);
DOT 1 (-6950 1675);
DOT 1 (-6950 1625);
DOT 1 (-6950 1575);
DOT 1 (-6950 1525);
DOT 1 (-6950 1475);
DOT 1 (-6950 1425);
DOT 1 (-6950 1375);
DOT 1 (-6950 1325);
DOT 1 (-6950 1275);
DOT 1 (-6950 1225);
DOT 1 (-6950 1175);
DOT 1 (-6950 1125);
DOT 1 (-6950 1075);
DOT 1 (-6950 1025);
DOT 1 (-6950 975);
DOT 1 (-6950 925);
DOT 1 (-6950 875);
DOT 1 (-6950 825);
DOT 1 (-6950 775);
DOT 1 (-2050 5975);
DOT 1 (-2050 6025);
DOT 1 (-2050 6075);
DOT 1 (-2050 6125);
DOT 1 (-2050 6225);
DOT 1 (-2050 6175);
DOT 1 (-2050 6275);
DOT 1 (-2050 6325);
DOT 1 (-2050 6375);
DOT 1 (-2050 6475);
DOT 1 (-2050 6425);
DOT 1 (-2050 4975);
DOT 1 (-2050 5075);
DOT 1 (-2050 5025);
DOT 1 (-2050 5125);
DOT 1 (-2050 5175);
DOT 1 (-2050 5225);
DOT 1 (-2050 5325);
DOT 1 (-2050 5375);
DOT 1 (-2050 5275);
DOT 1 (-2050 5475);
DOT 1 (-2050 5425);
DOT 1 (-2050 5625);
DOT 1 (-2050 5575);
DOT 1 (-2050 5525);
DOT 1 (-2050 5725);
DOT 1 (-2050 5675);
DOT 1 (-2050 5875);
DOT 1 (-2050 5775);
DOT 1 (-2050 5825);
DOT 1 (-2050 5925);
DOT 1 (-2050 3925);
DOT 1 (-2050 3975);
DOT 1 (-2050 4075);
DOT 1 (-2050 4025);
DOT 1 (-2050 4175);
DOT 1 (-2050 4125);
DOT 1 (-2050 4225);
DOT 1 (-2050 4325);
DOT 1 (-2050 4275);
DOT 1 (-2050 4475);
DOT 1 (-2050 4425);
DOT 1 (-2050 4375);
DOT 1 (-2050 4575);
DOT 1 (-2050 4525);
DOT 1 (-2050 4625);
DOT 1 (-2050 4725);
DOT 1 (-2050 4675);
DOT 1 (-2050 4825);
DOT 1 (-2050 4775);
DOT 1 (-2050 4875);
DOT 1 (-2050 4925);
DOT 1 (-2050 2925);
DOT 1 (-2050 2975);
DOT 1 (-2050 3175);
DOT 1 (-2050 3225);
DOT 1 (-2050 3275);
DOT 1 (-2050 3325);
DOT 1 (-2050 3425);
DOT 1 (-2050 3375);
DOT 1 (-2050 3575);
DOT 1 (-2050 3525);
DOT 1 (-2050 3475);
DOT 1 (-2050 3675);
DOT 1 (-2050 3625);
DOT 1 (-2050 3725);
DOT 1 (-2050 3825);
DOT 1 (-2050 1875);
DOT 1 (-2050 1925);
DOT 1 (-2050 2025);
DOT 1 (-2050 1975);
DOT 1 (-2050 2075);
DOT 1 (-2050 2175);
DOT 1 (-2050 2125);
DOT 1 (-2050 2275);
DOT 1 (-2050 2225);
DOT 1 (-2050 2425);
DOT 1 (-2050 2375);
DOT 1 (-2050 2325);
DOT 1 (-2050 2525);
DOT 1 (-2050 2475);
DOT 1 (-2050 2575);
DOT 1 (-2050 2625);
DOT 1 (-2050 2775);
DOT 1 (-2050 2825);
DOT 1 (-2050 2875);
DOT 1 (-2050 875);
DOT 1 (-2050 975);
DOT 1 (-2050 925);
DOT 1 (-2050 1075);
DOT 1 (-2050 1125);
DOT 1 (-2050 1275);
DOT 1 (-2050 1225);
DOT 1 (-2050 1175);
DOT 1 (-2050 1375);
DOT 1 (-2050 1325);
DOT 1 (-2050 1475);
DOT 1 (-2050 1425);
DOT 1 (-2050 1625);
DOT 1 (-2050 1575);
DOT 1 (-2050 1675);
DOT 1 (-2050 1775);
DOT 1 (-2050 1725);
DOT 1 (-2050 1825);
DOT 1 (-2050 825);
DOT 1 (-3550 6475);
DOT 1 (-3550 6425);
DOT 1 (-3550 6375);
DOT 1 (-3550 6325);
DOT 1 (-3550 6275);
DOT 1 (-3550 6225);
DOT 1 (-3550 6175);
DOT 1 (-3550 6125);
DOT 1 (-3550 6075);
DOT 1 (-3550 6025);
DOT 1 (-3550 5975);
DOT 1 (-3550 5875);
DOT 1 (-3550 5825);
DOT 1 (-3550 5725);
DOT 1 (-3550 5775);
DOT 1 (-3550 5675);
DOT 1 (-3550 5625);
DOT 1 (-3550 5575);
DOT 1 (-3550 5475);
DOT 1 (-3550 5525);
DOT 1 (-3550 5425);
DOT 1 (-3550 5375);
DOT 1 (-3550 5325);
DOT 1 (-3550 5225);
DOT 1 (-3550 5275);
DOT 1 (-3550 5175);
DOT 1 (-3550 5125);
DOT 1 (-3550 5075);
DOT 1 (-3550 4975);
DOT 1 (-3550 5025);
DOT 1 (-3550 4925);
DOT 1 (-3550 4825);
DOT 1 (-3550 4775);
DOT 1 (-3550 4725);
DOT 1 (-3550 4625);
DOT 1 (-3550 4575);
DOT 1 (-3550 4525);
DOT 1 (-3550 4475);
DOT 1 (-3550 4425);
DOT 1 (-3550 4375);
DOT 1 (-3550 4325);
DOT 1 (-3550 4275);
DOT 1 (-3550 4225);
DOT 1 (-3550 4175);
DOT 1 (-3550 4125);
DOT 1 (-3550 4075);
DOT 1 (-3550 4025);
DOT 1 (-3550 3975);
DOT 1 (-3550 3925);
DOT 1 (-3550 3875);
DOT 1 (-3550 3825);
DOT 1 (-3550 3675);
DOT 1 (-3550 3775);
DOT 1 (-3550 3725);
DOT 1 (-3550 3625);
DOT 1 (-3550 3575);
DOT 1 (-3550 3525);
DOT 1 (-3550 3425);
DOT 1 (-3550 3475);
DOT 1 (-3550 3375);
DOT 1 (-3550 3325);
DOT 1 (-3550 3275);
DOT 1 (-3550 3175);
DOT 1 (-3550 3225);
DOT 1 (-3550 3125);
DOT 1 (-3550 3075);
DOT 1 (-3550 3025);
DOT 1 (-3550 2925);
DOT 1 (-3550 2975);
DOT 1 (-3550 2875);
DOT 1 (-3550 2825);
DOT 1 (-3550 2775);
DOT 1 (-3550 2725);
DOT 1 (-3725 2475);
DOT 1 (-3725 2425);
DOT 1 (-3725 2375);
DOT 1 (-3725 2275);
DOT 1 (-3725 2325);
DOT 1 (-3725 2225);
DOT 1 (-3725 2175);
DOT 1 (-3725 2125);
DOT 1 (-3725 2025);
DOT 1 (-3725 2075);
DOT 1 (-3725 1975);
DOT 1 (-3725 1925);
DOT 1 (-3725 1875);
DOT 1 (-3725 1775);
DOT 1 (-3725 1825);
DOT 1 (-3725 1725);
DOT 1 (-3725 1675);
DOT 1 (-3725 1625);
DOT 1 (-3725 1575);
DOT 1 (-3725 1525);
DOT 1 (-3725 1475);
DOT 1 (-5525 2125);
DOT 1 (-3550 5925);
DOT 1 (-3725 2575);
DOT 1 (-1450 575);
DOT 1 (-7425 6350);
QUIT
